FILE_TYPE = MACRO_DRAWING;
SET COLOR_WIRE YELLOW;
SET COLOR_PROP MONO;
SET COLOR_DOT WHITE;
SET COLOR_ARC YELLOW;
SET COLOR_BODY GREEN;
SET COLOR_NOTE MONO;
SET PROP_DISPLAY VALUE;
SET PAGE_NUMBER P113;
FORCEADD NC7SB3157..1
R 2
(-2075 3525);
FORCEPROP 2 LASTPIN (-2425 3525) $PN 4
J 2
(-2435 3535);
DISPLAY 0.617021 (-2435 3535);
PAINT ORANGE (-2435 3535);
FORCEPROP 2 LASTPIN (-2425 3375) $PN 2
J 2
(-2435 3385);
DISPLAY 0.617021 (-2435 3385);
PAINT ORANGE (-2435 3385);
FORCEPROP 1 LAST PART_NUMBER C99406-001
J 2
(-1775 3750);
DISPLAY 0.617021 (-1775 3750);
PAINT BLUE (-1775 3750);
FORCEPROP 1 LAST PACK_TYPE SMLF
J 2
(-1900 3275);
DISPLAY 0.617021 (-1900 3275);
PAINT SKYBLUE (-1900 3275);
FORCEPROP 1 LAST MATERIAL IC
J 2
(-1775 3275);
DISPLAY 0.617021 (-1775 3275);
PAINT SKYBLUE (-1775 3275);
FORCEPROP 2 LASTPIN (-1725 3475) $PN 1
J 0
(-1715 3485);
DISPLAY 0.617021 (-1715 3485);
PAINT ORANGE (-1715 3485);
FORCEPROP 2 LASTPIN (-1725 3375) $PN 5
J 0
(-1715 3385);
DISPLAY 0.617021 (-1715 3385);
PAINT ORANGE (-1715 3385);
FORCEPROP 2 LASTPIN (-1725 3575) $PN 3
J 0
(-1715 3585);
DISPLAY 0.617021 (-1715 3585);
PAINT ORANGE (-1715 3585);
FORCEPROP 2 LASTPIN (-1725 3675) $PN 6
J 0
(-1715 3685);
DISPLAY 0.617021 (-1715 3685);
PAINT ORANGE (-1715 3685);
FORCEPROP 1 LAST LOCATION U1M2
J 2
(-1775 3800);
DISPLAY 0.617021 (-1775 3800);
PAINT AQUA (-1775 3800);
FORCEPROP 1 LAST PATH I107
J 2
(-2150 3275);
DISPLAY 0.851064 (-2150 3275);
PAINT WHITE (-2150 3275);
DISPLAY INVISIBLE (-2150 3275);
FORCEPROP 2 LAST CDS_LIB mstr_analog
J 0
(-2075 3525);
PAINT MONO (-2075 3525);
DISPLAY INVISIBLE (-2075 3525);
FORCEPROP 2 LAST ROOM DEBUG
J 0
(-1775 3850);
DISPLAY 1.617021 (-1775 3850);
PAINT WHITE (-1775 3850);
DISPLAY INVISIBLE (-1775 3850);
FORCEPROP 2 LAST SEC 1
J 0
(-1775 3850);
DISPLAY 0.680851 (-1775 3850);
PAINT MONO (-1775 3850);
DISPLAY INVISIBLE (-1775 3850);
FORCEPROP 2 LAST SEC_TYPE SMLF
J 0
(-1775 3850);
DISPLAY 1.021277 (-1775 3850);
PAINT ORANGE (-1775 3850);
DISPLAY INVISIBLE (-1775 3850);
FORCEPROP 2 LAST BOM_COST DEBUG
J 0
(-1775 3900);
DISPLAY 1.617021 (-1775 3900);
PAINT WHITE (-1775 3900);
DISPLAY INVISIBLE (-1775 3900);
FORCEADD GND..1
(-2500 3225);
FORCEPROP 3 LASTPIN (-2500 3275) SIG_NAME GND\g
J 0
(-2490 3285);
DISPLAY 0.659574 (-2490 3285);
PAINT MONO (-2490 3285);
DISPLAY INVISIBLE (-2490 3285);
FORCEPROP 2 LAST CDS_LIB mstr_symbols
J 0
(-2500 3225);
PAINT MONO (-2500 3225);
DISPLAY INVISIBLE (-2500 3225);
FORCEPROP 1 LAST VOLTAGE 0.0V
J 0
(-2545 3182);
DISPLAY 0.340426 (-2545 3182);
PAINT SKYBLUE (-2545 3182);
DISPLAY INVISIBLE (-2545 3182);
FORCEPROP 1 LAST PATH I109
J 0
(-2425 3225);
DISPLAY 0.872340 (-2425 3225);
PAINT AQUA (-2425 3225);
DISPLAY INVISIBLE (-2425 3225);
FORCEPROP 1 LAST SIZE 1B
J 0
(-2425 3175);
DISPLAY 0.872340 (-2425 3175);
PAINT AQUA (-2425 3175);
DISPLAY INVISIBLE (-2425 3175);
FORCEPROP 1 LAST BODY_TYPE PLUMBING
J 0
(-2545 3182);
DISPLAY 0.340426 (-2545 3182);
PAINT GREEN (-2545 3182);
DISPLAY INVISIBLE (-2545 3182);
FORCEPROP 1 LAST HDL_POWER GND
J 0
(-2500 3375);
DISPLAY 0.872340 (-2500 3375);
PAINT GREEN (-2500 3375);
DISPLAY INVISIBLE (-2500 3375);
FORCEADD GND..1
(-1150 4100);
FORCEPROP 3 LASTPIN (-1150 4150) SIG_NAME GND\g
J 0
(-1140 4160);
DISPLAY 0.659574 (-1140 4160);
PAINT MONO (-1140 4160);
DISPLAY INVISIBLE (-1140 4160);
FORCEPROP 1 LAST BODY_TYPE PLUMBING
J 0
(-1195 4057);
DISPLAY 0.340426 (-1195 4057);
PAINT GREEN (-1195 4057);
DISPLAY INVISIBLE (-1195 4057);
FORCEPROP 1 LAST SIZE 1B
J 0
(-1075 4050);
DISPLAY 0.872340 (-1075 4050);
PAINT AQUA (-1075 4050);
DISPLAY INVISIBLE (-1075 4050);
FORCEPROP 1 LAST VOLTAGE 0.0V
J 0
(-1195 4057);
DISPLAY 0.340426 (-1195 4057);
PAINT SKYBLUE (-1195 4057);
DISPLAY INVISIBLE (-1195 4057);
FORCEPROP 2 LAST CDS_LIB mstr_symbols
J 0
(-1150 4100);
PAINT MONO (-1150 4100);
DISPLAY INVISIBLE (-1150 4100);
FORCEPROP 1 LAST PATH I110
J 0
(-1075 4100);
DISPLAY 0.872340 (-1075 4100);
PAINT AQUA (-1075 4100);
DISPLAY INVISIBLE (-1075 4100);
FORCEPROP 1 LAST HDL_POWER GND
J 0
(-1150 4250);
DISPLAY 0.872340 (-1150 4250);
PAINT GREEN (-1150 4250);
DISPLAY INVISIBLE (-1150 4250);
FORCEADD OFFPAGE..4
(-1050 3675);
FORCEPROP 2 LAST $XR0 191 
J 0
(-864 3675);
DISPLAY 0.638298 (-864 3675);
PAINT MONO (-864 3675);
FORCEPROP 1 LAST COMMENT_BODY TRUE
J 0
(-1075 3575);
DISPLAY 0.872340 (-1075 3575);
PAINT GREEN (-1075 3575);
DISPLAY INVISIBLE (-1075 3575);
FORCEPROP 2 LAST CDS_LIB mstr_standard
J 0
(-1050 3675);
PAINT MONO (-1050 3675);
DISPLAY INVISIBLE (-1050 3675);
FORCEPROP 1 LAST OFFPAGE TRUE
J 0
(-725 3550);
DISPLAY 0.872340 (-725 3550);
PAINT GREEN (-725 3550);
DISPLAY INVISIBLE (-725 3550);
FORCEPROP 2 LAST PATH I111
J 0
(-875 3750);
DISPLAY 1.021277 (-875 3750);
PAINT ORANGE (-875 3750);
DISPLAY INVISIBLE (-875 3750);
FORCEADD OFFPAGE..2
(-750 850);
FORCEPROP 2 LAST $XR0 113 
J 0
(-561 850);
DISPLAY 0.638298 (-561 850);
PAINT MONO (-561 850);
FORCEPROP 2 LAST $XR1 63 
J 0
(-441 850);
DISPLAY 0.638298 (-441 850);
PAINT MONO (-441 850);
FORCEPROP 1 LAST COMMENT_BODY TRUE
J 0
(-795 755);
DISPLAY 0.872340 (-795 755);
PAINT GREEN (-795 755);
DISPLAY INVISIBLE (-795 755);
FORCEPROP 2 LAST CDS_LIB mstr_standard
J 0
(-750 850);
PAINT MONO (-750 850);
DISPLAY INVISIBLE (-750 850);
FORCEPROP 2 LAST PATH I112
J 0
(-575 925);
DISPLAY 1.021277 (-575 925);
PAINT ORANGE (-575 925);
DISPLAY INVISIBLE (-575 925);
FORCEPROP 1 LAST OFFPAGE TRUE
J 0
(-425 725);
DISPLAY 0.872340 (-425 725);
PAINT GREEN (-425 725);
DISPLAY INVISIBLE (-425 725);
FORCEADD OFFPAGE..1
(-2475 800);
FORCEPROP 2 LAST $XR0 191 
J 0
(-2757 800);
DISPLAY 0.638298 (-2757 800);
PAINT MONO (-2757 800);
FORCEPROP 1 LAST COMMENT_BODY TRUE
J 0
(-2350 700);
DISPLAY 0.872340 (-2350 700);
PAINT GREEN (-2350 700);
DISPLAY INVISIBLE (-2350 700);
FORCEPROP 2 LAST CDS_LIB mstr_standard
J 0
(-2475 800);
PAINT MONO (-2475 800);
DISPLAY INVISIBLE (-2475 800);
FORCEPROP 2 LAST PATH I113
J 0
(-2300 875);
DISPLAY 1.021277 (-2300 875);
PAINT ORANGE (-2300 875);
DISPLAY INVISIBLE (-2300 875);
FORCEPROP 1 LAST OFFPAGE TRUE
J 0
(-2150 675);
DISPLAY 0.872340 (-2150 675);
PAINT GREEN (-2150 675);
DISPLAY INVISIBLE (-2150 675);
FORCEADD CAP_A..1
R 2
(-1550 3025);
FORCEPROP 1 LAST PART_NUMBER A36096-045
J 2
(-1600 2875);
DISPLAY 0.617021 (-1600 2875);
PAINT BLUE (-1600 2875);
FORCEPROP 1 LAST PACK_TYPE 0402V
J 2
(-1600 2825);
DISPLAY 0.617021 (-1600 2825);
PAINT SKYBLUE (-1600 2825);
FORCEPROP 1 LAST TOLERANCE 10%
J 2
(-1600 2975);
DISPLAY 0.617021 (-1600 2975);
PAINT SKYBLUE (-1600 2975);
FORCEPROP 1 LAST VOLTAGE 25V
J 2
(-1600 3025);
DISPLAY 0.617021 (-1600 3025);
PAINT SKYBLUE (-1600 3025);
FORCEPROP 1 LAST MATERIAL X7R
J 2
(-1600 2925);
DISPLAY 0.617021 (-1600 2925);
PAINT SKYBLUE (-1600 2925);
FORCEPROP 1 LASTPIN (-1550 2925) $PN 2
J 2
(-1560 2905);
DISPLAY 0.617021 (-1560 2905);
PAINT ORANGE (-1560 2905);
FORCEPROP 1 LAST LOCATION C1M31
J 2
(-1600 3125);
DISPLAY 0.617021 (-1600 3125);
PAINT AQUA (-1600 3125);
FORCEPROP 1 LAST VALUE 0.01UF
J 2
(-1600 3075);
DISPLAY 0.617021 (-1600 3075);
PAINT SKYBLUE (-1600 3075);
FORCEPROP 1 LASTPIN (-1550 3125) $PN 1
J 2
(-1560 3105);
DISPLAY 0.617021 (-1560 3105);
PAINT ORANGE (-1560 3105);
FORCEPROP 2 LAST CDS_LIB dev_discrete
J 0
(-1550 3025);
PAINT ORANGE (-1550 3025);
DISPLAY INVISIBLE (-1550 3025);
FORCEPROP 2 LAST CDS_SEC 1
J 0
(-1600 3175);
PAINT ORANGE (-1600 3175);
DISPLAY INVISIBLE (-1600 3175);
FORCEPROP 2 LAST BOM_COST DEBUG
J 0
(-1600 3175);
DISPLAY 1.617021 (-1600 3175);
PAINT WHITE (-1600 3175);
DISPLAY INVISIBLE (-1600 3175);
FORCEPROP 1 LAST PATH I116
J 2
(-1600 3175);
DISPLAY 0.978723 (-1600 3175);
PAINT WHITE (-1600 3175);
DISPLAY INVISIBLE (-1600 3175);
FORCEPROP 2 LAST ROOM DEBUG
J 2
(-1600 3175);
DISPLAY 1.617021 (-1600 3175);
PAINT WHITE (-1600 3175);
DISPLAY INVISIBLE (-1600 3175);
FORCEPROP 2 LAST SEC 1
J 0
(-1600 3225);
DISPLAY 0.680851 (-1600 3225);
PAINT MONO (-1600 3225);
DISPLAY INVISIBLE (-1600 3225);
FORCEPROP 2 LAST SEC_TYPE 0402V
J 0
(-1600 3225);
DISPLAY 1.021277 (-1600 3225);
PAINT ORANGE (-1600 3225);
DISPLAY INVISIBLE (-1600 3225);
FORCEADD CAP_A..1
R 2
(-1250 3025);
FORCEPROP 1 LAST PART_NUMBER D97712-004
J 2
(-1300 2875);
DISPLAY 0.617021 (-1300 2875);
PAINT BLUE (-1300 2875);
FORCEPROP 1 LAST MATERIAL X6S
J 2
(-1300 2925);
DISPLAY 0.617021 (-1300 2925);
PAINT SKYBLUE (-1300 2925);
FORCEPROP 1 LAST VOLTAGE 6.3V
J 2
(-1300 3025);
DISPLAY 0.617021 (-1300 3025);
PAINT SKYBLUE (-1300 3025);
FORCEPROP 1 LAST PACK_TYPE 0402V
J 2
(-1300 2825);
DISPLAY 0.617021 (-1300 2825);
PAINT SKYBLUE (-1300 2825);
FORCEPROP 1 LAST TOLERANCE 10%
J 2
(-1300 2975);
DISPLAY 0.617021 (-1300 2975);
PAINT SKYBLUE (-1300 2975);
FORCEPROP 1 LASTPIN (-1250 2925) $PN 2
J 2
(-1260 2905);
DISPLAY 0.617021 (-1260 2905);
PAINT ORANGE (-1260 2905);
FORCEPROP 1 LAST VALUE 1.0UF
J 2
(-1300 3075);
DISPLAY 0.617021 (-1300 3075);
PAINT SKYBLUE (-1300 3075);
FORCEPROP 1 LAST LOCATION C1M32
J 2
(-1300 3125);
DISPLAY 0.617021 (-1300 3125);
PAINT AQUA (-1300 3125);
FORCEPROP 1 LASTPIN (-1250 3125) $PN 1
J 2
(-1260 3105);
DISPLAY 0.617021 (-1260 3105);
PAINT ORANGE (-1260 3105);
FORCEPROP 2 LAST CDS_LIB dev_discrete
J 0
(-1250 3025);
PAINT ORANGE (-1250 3025);
DISPLAY INVISIBLE (-1250 3025);
FORCEPROP 2 LAST ROOM DEBUG
J 2
(-1300 3175);
DISPLAY 1.617021 (-1300 3175);
PAINT WHITE (-1300 3175);
DISPLAY INVISIBLE (-1300 3175);
FORCEPROP 1 LAST PATH I117
J 2
(-1300 3175);
DISPLAY 0.978723 (-1300 3175);
PAINT WHITE (-1300 3175);
DISPLAY INVISIBLE (-1300 3175);
FORCEPROP 2 LAST SEC 1
J 0
(-1300 3225);
DISPLAY 0.680851 (-1300 3225);
PAINT MONO (-1300 3225);
DISPLAY INVISIBLE (-1300 3225);
FORCEPROP 2 LAST SEC_TYPE 0402V
J 0
(-1300 3225);
DISPLAY 1.021277 (-1300 3225);
PAINT ORANGE (-1300 3225);
DISPLAY INVISIBLE (-1300 3225);
FORCEPROP 2 LAST CDS_SEC 1
J 0
(-1300 3175);
PAINT ORANGE (-1300 3175);
DISPLAY INVISIBLE (-1300 3175);
FORCEPROP 2 LAST BOM_COST DEBUG
J 0
(-1300 3175);
DISPLAY 1.617021 (-1300 3175);
PAINT WHITE (-1300 3175);
DISPLAY INVISIBLE (-1300 3175);
FORCEADD GND..1
(-1250 2725);
FORCEPROP 3 LASTPIN (-1250 2775) SIG_NAME GND\g
J 0
(-1240 2785);
DISPLAY 0.659574 (-1240 2785);
PAINT MONO (-1240 2785);
DISPLAY INVISIBLE (-1240 2785);
FORCEPROP 2 LAST BOM_COST DEBUG
J 0
(-1725 2850);
DISPLAY 1.617021 (-1725 2850);
PAINT WHITE (-1725 2850);
DISPLAY INVISIBLE (-1725 2850);
FORCEPROP 2 LAST ROOM DEBUG
J 0
(-1725 2800);
DISPLAY 1.617021 (-1725 2800);
PAINT WHITE (-1725 2800);
DISPLAY INVISIBLE (-1725 2800);
FORCEPROP 1 LAST VOLTAGE 0.0V
J 0
(-1295 2682);
DISPLAY 0.340426 (-1295 2682);
PAINT SKYBLUE (-1295 2682);
DISPLAY INVISIBLE (-1295 2682);
FORCEPROP 1 LAST BODY_TYPE PLUMBING
J 0
(-1295 2682);
DISPLAY 0.340426 (-1295 2682);
PAINT GREEN (-1295 2682);
DISPLAY INVISIBLE (-1295 2682);
FORCEPROP 1 LAST SIZE 1B
J 0
(-1175 2675);
DISPLAY 1.893617 (-1175 2675);
PAINT GREEN (-1175 2675);
DISPLAY INVISIBLE (-1175 2675);
FORCEPROP 2 LAST CDS_LIB mstr_symbols
J 0
(-1250 2725);
PAINT MONO (-1250 2725);
DISPLAY INVISIBLE (-1250 2725);
FORCEPROP 1 LAST PATH I118
J 0
(-1175 2725);
DISPLAY 0.872340 (-1175 2725);
PAINT AQUA (-1175 2725);
DISPLAY INVISIBLE (-1175 2725);
FORCEPROP 1 LAST HDL_POWER GND
J 0
(-1250 2875);
PAINT GREEN (-1250 2875);
DISPLAY INVISIBLE (-1250 2875);
FORCEADD CAP_A..1
R 2
(-2250 1250);
FORCEPROP 1 LAST PART_NUMBER A36096-045
J 2
(-2300 1100);
DISPLAY 0.617021 (-2300 1100);
PAINT BLUE (-2300 1100);
FORCEPROP 1 LAST MATERIAL X7R
J 2
(-2300 1150);
DISPLAY 0.617021 (-2300 1150);
PAINT SKYBLUE (-2300 1150);
FORCEPROP 1 LAST VOLTAGE 25V
J 2
(-2300 1250);
DISPLAY 0.617021 (-2300 1250);
PAINT SKYBLUE (-2300 1250);
FORCEPROP 1 LAST PACK_TYPE 0402V
J 2
(-2300 1050);
DISPLAY 0.617021 (-2300 1050);
PAINT SKYBLUE (-2300 1050);
FORCEPROP 1 LAST TOLERANCE 10%
J 2
(-2300 1200);
DISPLAY 0.617021 (-2300 1200);
PAINT SKYBLUE (-2300 1200);
FORCEPROP 1 LAST VALUE 0.01UF
J 2
(-2300 1300);
DISPLAY 0.617021 (-2300 1300);
PAINT SKYBLUE (-2300 1300);
FORCEPROP 1 LAST LOCATION C1M28
J 2
(-2300 1350);
DISPLAY 0.617021 (-2300 1350);
PAINT AQUA (-2300 1350);
FORCEPROP 1 LASTPIN (-2250 1150) $PN 2
J 2
(-2260 1130);
DISPLAY 0.617021 (-2260 1130);
PAINT ORANGE (-2260 1130);
FORCEPROP 1 LASTPIN (-2250 1350) $PN 1
J 2
(-2260 1330);
DISPLAY 0.617021 (-2260 1330);
PAINT ORANGE (-2260 1330);
FORCEPROP 2 LAST CDS_LIB dev_discrete
J 0
(-2250 1250);
PAINT ORANGE (-2250 1250);
DISPLAY INVISIBLE (-2250 1250);
FORCEPROP 2 LAST ROOM DEBUG
J 2
(-2300 1400);
DISPLAY 1.617021 (-2300 1400);
PAINT WHITE (-2300 1400);
DISPLAY INVISIBLE (-2300 1400);
FORCEPROP 1 LAST PATH I119
J 2
(-2300 1400);
DISPLAY 0.978723 (-2300 1400);
PAINT WHITE (-2300 1400);
DISPLAY INVISIBLE (-2300 1400);
FORCEPROP 2 LAST CDS_SEC 1
J 0
(-2300 1400);
PAINT ORANGE (-2300 1400);
DISPLAY INVISIBLE (-2300 1400);
FORCEPROP 2 LAST BOM_COST DEBUG
J 0
(-2300 1400);
DISPLAY 1.617021 (-2300 1400);
PAINT WHITE (-2300 1400);
DISPLAY INVISIBLE (-2300 1400);
FORCEPROP 2 LAST SEC 1
J 0
(-2300 1450);
DISPLAY 0.680851 (-2300 1450);
PAINT MONO (-2300 1450);
DISPLAY INVISIBLE (-2300 1450);
FORCEPROP 2 LAST SEC_TYPE 0402V
J 0
(-2300 1450);
DISPLAY 1.021277 (-2300 1450);
PAINT ORANGE (-2300 1450);
DISPLAY INVISIBLE (-2300 1450);
FORCEADD GND..1
(-2250 1050);
FORCEPROP 3 LASTPIN (-2250 1100) SIG_NAME GND\g
J 0
(-2240 1110);
DISPLAY 0.659574 (-2240 1110);
PAINT MONO (-2240 1110);
DISPLAY INVISIBLE (-2240 1110);
FORCEPROP 1 LAST BODY_TYPE PLUMBING
J 0
(-2295 1007);
DISPLAY 0.340426 (-2295 1007);
PAINT GREEN (-2295 1007);
DISPLAY INVISIBLE (-2295 1007);
FORCEPROP 1 LAST VOLTAGE 0.0V
J 0
(-2295 1007);
DISPLAY 0.340426 (-2295 1007);
PAINT SKYBLUE (-2295 1007);
DISPLAY INVISIBLE (-2295 1007);
FORCEPROP 1 LAST SIZE 1B
J 0
(-2175 1000);
DISPLAY 1.893617 (-2175 1000);
PAINT GREEN (-2175 1000);
DISPLAY INVISIBLE (-2175 1000);
FORCEPROP 2 LAST ROOM DEBUG
J 0
(-2725 1125);
DISPLAY 1.617021 (-2725 1125);
PAINT WHITE (-2725 1125);
DISPLAY INVISIBLE (-2725 1125);
FORCEPROP 2 LAST BOM_COST DEBUG
J 0
(-2725 1175);
DISPLAY 1.617021 (-2725 1175);
PAINT WHITE (-2725 1175);
DISPLAY INVISIBLE (-2725 1175);
FORCEPROP 2 LAST CDS_LIB mstr_symbols
J 0
(-2250 1050);
PAINT MONO (-2250 1050);
DISPLAY INVISIBLE (-2250 1050);
FORCEPROP 1 LAST HDL_POWER GND
J 0
(-2250 1200);
PAINT GREEN (-2250 1200);
DISPLAY INVISIBLE (-2250 1200);
FORCEPROP 1 LAST PATH I121
J 0
(-2175 1050);
DISPLAY 0.872340 (-2175 1050);
PAINT AQUA (-2175 1050);
DISPLAY INVISIBLE (-2175 1050);
FORCEADD OFFPAGE..5
(-3125 4625);
FORCEPROP 2 LAST $XR0 29 
J 0
(-3349 4625);
DISPLAY 0.638298 (-3349 4625);
PAINT MONO (-3349 4625);
FORCEPROP 2 LAST $XR1 63 
J 0
(-3439 4625);
DISPLAY 0.638298 (-3439 4625);
PAINT MONO (-3439 4625);
FORCEPROP 2 LAST $XR2 113 
J 0
(-3559 4625);
DISPLAY 0.638298 (-3559 4625);
PAINT MONO (-3559 4625);
FORCEPROP 2 LAST CDS_LIB mstr_standard
J 0
(-3125 4625);
PAINT MONO (-3125 4625);
DISPLAY INVISIBLE (-3125 4625);
FORCEPROP 2 LAST PATH I124
J 0
(-3075 4700);
DISPLAY 1.021277 (-3075 4700);
PAINT ORANGE (-3075 4700);
DISPLAY INVISIBLE (-3075 4700);
FORCEPROP 1 LAST COMMENT_BODY TRUE
J 0
(-3025 4550);
DISPLAY 0.872340 (-3025 4550);
PAINT GREEN (-3025 4550);
DISPLAY INVISIBLE (-3025 4550);
FORCEPROP 1 LAST OFFPAGE TRUE
J 0
(-2800 4500);
DISPLAY 0.872340 (-2800 4500);
PAINT GREEN (-2800 4500);
DISPLAY INVISIBLE (-2800 4500);
FORCEADD OFFPAGE..5
(-3125 4375);
FORCEPROP 2 LAST $XR0 113 
J 0
(-3380 4375);
DISPLAY 0.638298 (-3380 4375);
PAINT MONO (-3380 4375);
FORCEPROP 2 LAST $XR1 29 
J 0
(-3470 4375);
DISPLAY 0.638298 (-3470 4375);
PAINT MONO (-3470 4375);
FORCEPROP 2 LAST $XR2 63 
J 0
(-3560 4375);
DISPLAY 0.638298 (-3560 4375);
PAINT MONO (-3560 4375);
FORCEPROP 2 LAST CDS_LIB mstr_standard
J 0
(-3125 4375);
PAINT MONO (-3125 4375);
DISPLAY INVISIBLE (-3125 4375);
FORCEPROP 2 LAST PATH I126
J 0
(-3075 4450);
DISPLAY 1.021277 (-3075 4450);
PAINT ORANGE (-3075 4450);
DISPLAY INVISIBLE (-3075 4450);
FORCEPROP 1 LAST COMMENT_BODY TRUE
J 0
(-3025 4300);
DISPLAY 0.872340 (-3025 4300);
PAINT GREEN (-3025 4300);
DISPLAY INVISIBLE (-3025 4300);
FORCEPROP 1 LAST OFFPAGE TRUE
J 0
(-2800 4250);
DISPLAY 0.872340 (-2800 4250);
PAINT GREEN (-2800 4250);
DISPLAY INVISIBLE (-2800 4250);
FORCEADD 74CBTLV1G125..1
(-1500 850);
FORCEPROP 2 LASTPIN (-1750 850) $PN 2
J 2
(-1760 860);
DISPLAY 0.617021 (-1760 860);
PAINT ORANGE (-1760 860);
FORCEPROP 2 LASTPIN (-1750 800) $PN 1
J 2
(-1760 810);
DISPLAY 0.617021 (-1760 810);
PAINT ORANGE (-1760 810);
FORCEPROP 1 LAST LOCATION U1M6
J 0
(-1666 981);
DISPLAY 0.617021 (-1666 981);
PAINT AQUA (-1666 981);
FORCEPROP 1 LAST PART_NUMBER C88177-001
J 0
(-1665 710);
DISPLAY 0.617021 (-1665 710);
PAINT BLUE (-1665 710);
FORCEPROP 1 LAST POWER_GROUP VCC=P3V3_STBY;GND=GND;
J 0
(-1725 650);
DISPLAY 0.617021 (-1725 650);
PAINT ORANGE (-1725 650);
FORCEPROP 2 LASTPIN (-1250 850) $PN 4
J 0
(-1240 860);
DISPLAY 0.617021 (-1240 860);
PAINT ORANGE (-1240 860);
FORCEPROP 1 LAST PACK_TYPE SMLF
J 0
(-1675 1020);
DISPLAY 0.617021 (-1675 1020);
PAINT SKYBLUE (-1675 1020);
FORCEPROP 1 LAST MATERIAL IC
J 0
(-1675 1070);
DISPLAY 0.617021 (-1675 1070);
PAINT SKYBLUE (-1675 1070);
FORCEPROP 1 LAST PATH I127
J 0
(-1400 970);
DISPLAY 0.872340 (-1400 970);
PAINT PINK (-1400 970);
DISPLAY INVISIBLE (-1400 970);
FORCEPROP 2 LAST CDS_LIB mstr_ttl
J 0
(-1500 850);
PAINT MONO (-1500 850);
DISPLAY INVISIBLE (-1500 850);
FORCEPROP 2 LAST ROOM DEBUG
J 0
(-1675 1175);
DISPLAY 1.021277 (-1675 1175);
PAINT ORANGE (-1675 1175);
DISPLAY INVISIBLE (-1675 1175);
FORCEPROP 2 LAST SEC 1
J 0
(-1675 1100);
DISPLAY 0.680851 (-1675 1100);
PAINT MONO (-1675 1100);
DISPLAY INVISIBLE (-1675 1100);
FORCEPROP 2 LAST SEC_TYPE SMLF
J 0
(-1675 1100);
DISPLAY 1.021277 (-1675 1100);
PAINT ORANGE (-1675 1100);
DISPLAY INVISIBLE (-1675 1100);
FORCEPROP 2 LAST BOM_COST DEBUG
J 0
(-1675 1175);
DISPLAY 1.021277 (-1675 1175);
PAINT ORANGE (-1675 1175);
DISPLAY INVISIBLE (-1675 1175);
FORCEADD OFFPAGE..1
(-2475 850);
FORCEPROP 2 LAST $XR0 29 
J 0
(-2726 850);
DISPLAY 0.638298 (-2726 850);
PAINT MONO (-2726 850);
FORCEPROP 2 LAST $XR1 113 
J 0
(-2846 850);
DISPLAY 0.638298 (-2846 850);
PAINT MONO (-2846 850);
FORCEPROP 1 LAST COMMENT_BODY TRUE
J 0
(-2350 750);
DISPLAY 0.872340 (-2350 750);
PAINT GREEN (-2350 750);
DISPLAY INVISIBLE (-2350 750);
FORCEPROP 2 LAST CDS_LIB mstr_standard
J 0
(-2475 850);
PAINT MONO (-2475 850);
DISPLAY INVISIBLE (-2475 850);
FORCEPROP 2 LAST PATH I128
J 0
(-2425 925);
DISPLAY 1.021277 (-2425 925);
PAINT ORANGE (-2425 925);
DISPLAY INVISIBLE (-2425 925);
FORCEPROP 1 LAST OFFPAGE TRUE
J 0
(-2150 725);
DISPLAY 0.872340 (-2150 725);
PAINT GREEN (-2150 725);
DISPLAY INVISIBLE (-2150 725);
FORCEADD RES..2
R 2
(2450 3200);
FORCEPROP 1 LAST PACK_TYPE 0402
J 2
(2410 3025);
DISPLAY 0.617021 (2410 3025);
PAINT SKYBLUE (2410 3025);
FORCEPROP 1 LAST WATTAGE 1/16W
J 2
(2410 3175);
DISPLAY 0.617021 (2410 3175);
PAINT SKYBLUE (2410 3175);
FORCEPROP 1 LAST MATERIAL CHIP
J 2
(2410 3125);
DISPLAY 0.617021 (2410 3125);
PAINT SKYBLUE (2410 3125);
FORCEPROP 1 LAST VALUE 49.9
J 2
(2405 3275);
DISPLAY 0.617021 (2405 3275);
PAINT SKYBLUE (2405 3275);
FORCEPROP 1 LAST PART_NUMBER G21796-047
J 2
(2410 3075);
DISPLAY 0.617021 (2410 3075);
PAINT BLUE (2410 3075);
FORCEPROP 1 LAST LOCATION R4R6
J 2
(2405 3325);
DISPLAY 0.617021 (2405 3325);
PAINT AQUA (2405 3325);
FORCEPROP 1 LAST TOLERANCE 1%
J 2
(2405 3225);
DISPLAY 0.617021 (2405 3225);
PAINT SKYBLUE (2405 3225);
FORCEPROP 1 LASTPIN (2450 3100) $PN 2
J 2
(2445 3110);
DISPLAY 0.617021 (2445 3110);
PAINT ORANGE (2445 3110);
FORCEPROP 1 LASTPIN (2450 3300) $PN 1
J 2
(2445 3262);
DISPLAY 0.617021 (2445 3262);
PAINT ORANGE (2445 3262);
FORCEPROP 2 LAST CDS_LIB mstr_discrete
J 0
(2450 3200);
PAINT ORANGE (2450 3200);
DISPLAY INVISIBLE (2450 3200);
FORCEPROP 2 LAST SEC_TYPE 0402
J 0
(2400 3425);
DISPLAY 1.021277 (2400 3425);
PAINT ORANGE (2400 3425);
DISPLAY INVISIBLE (2400 3425);
FORCEPROP 2 LAST SEC 1
J 0
(2400 3425);
DISPLAY 0.680851 (2400 3425);
PAINT MONO (2400 3425);
DISPLAY INVISIBLE (2400 3425);
FORCEPROP 1 LAST PATH I134
J 2
(2400 3375);
DISPLAY 0.978723 (2400 3375);
PAINT WHITE (2400 3375);
DISPLAY INVISIBLE (2400 3375);
FORCEPROP 2 LAST ROOM DEBUG
J 2
(2405 3365);
DISPLAY 1.276596 (2405 3365);
PAINT WHITE (2405 3365);
DISPLAY INVISIBLE (2405 3365);
FORCEADD OFFPAGE..1
(2200 4400);
FORCEPROP 2 LAST $XR0 113 
J 0
(1948 4400);
DISPLAY 0.638298 (1948 4400);
PAINT MONO (1948 4400);
FORCEPROP 2 LAST $XR1 29 
J 0
(1858 4400);
DISPLAY 0.638298 (1858 4400);
PAINT MONO (1858 4400);
FORCEPROP 2 LAST $XR2 63 
J 0
(1768 4400);
DISPLAY 0.638298 (1768 4400);
PAINT MONO (1768 4400);
FORCEPROP 2 LAST PATH I143
J 0
(2250 4475);
DISPLAY 1.021277 (2250 4475);
PAINT ORANGE (2250 4475);
DISPLAY INVISIBLE (2250 4475);
FORCEPROP 2 LAST CDS_LIB mstr_standard
J 0
(2200 4400);
PAINT MONO (2200 4400);
DISPLAY INVISIBLE (2200 4400);
FORCEPROP 1 LAST COMMENT_BODY TRUE
J 0
(2325 4300);
DISPLAY 1.404255 (2325 4300);
PAINT PEACH (2325 4300);
DISPLAY INVISIBLE (2325 4300);
FORCEPROP 1 LAST OFFPAGE TRUE
J 0
(2525 4275);
DISPLAY 1.404255 (2525 4275);
PAINT GREEN (2525 4275);
DISPLAY INVISIBLE (2525 4275);
FORCEADD GND..1
(-975 4450);
FORCEPROP 3 LASTPIN (-975 4500) SIG_NAME GND\g
J 0
(-965 4510);
DISPLAY 0.659574 (-965 4510);
PAINT MONO (-965 4510);
DISPLAY INVISIBLE (-965 4510);
FORCEPROP 2 LAST ROOM DEBUG
J 0
(-1450 4525);
DISPLAY 1.617021 (-1450 4525);
PAINT WHITE (-1450 4525);
DISPLAY INVISIBLE (-1450 4525);
FORCEPROP 2 LAST BOM_COST DEBUG
J 0
(-1450 4575);
DISPLAY 1.617021 (-1450 4575);
PAINT WHITE (-1450 4575);
DISPLAY INVISIBLE (-1450 4575);
FORCEPROP 1 LAST VOLTAGE 0.0V
J 0
(-1020 4407);
DISPLAY 0.340426 (-1020 4407);
PAINT SKYBLUE (-1020 4407);
DISPLAY INVISIBLE (-1020 4407);
FORCEPROP 1 LAST SIZE 1B
J 0
(-900 4400);
DISPLAY 1.893617 (-900 4400);
PAINT GREEN (-900 4400);
DISPLAY INVISIBLE (-900 4400);
FORCEPROP 1 LAST BODY_TYPE PLUMBING
J 0
(-1020 4407);
DISPLAY 0.340426 (-1020 4407);
PAINT GREEN (-1020 4407);
DISPLAY INVISIBLE (-1020 4407);
FORCEPROP 2 LAST CDS_LIB mstr_symbols
J 0
(-975 4450);
PAINT MONO (-975 4450);
DISPLAY INVISIBLE (-975 4450);
FORCEPROP 1 LAST PATH I146
J 0
(-900 4450);
DISPLAY 0.872340 (-900 4450);
PAINT AQUA (-900 4450);
DISPLAY INVISIBLE (-900 4450);
FORCEPROP 1 LAST HDL_POWER GND
J 0
(-975 4600);
PAINT GREEN (-975 4600);
DISPLAY INVISIBLE (-975 4600);
FORCEADD CAP_A..1
(-975 4650);
FORCEPROP 1 LASTPIN (-975 4550) $PN 2
J 0
(-965 4530);
DISPLAY 0.617021 (-965 4530);
PAINT ORANGE (-965 4530);
FORCEPROP 1 LAST MATERIAL X7R
J 0
(-925 4550);
DISPLAY 0.617021 (-925 4550);
PAINT SKYBLUE (-925 4550);
FORCEPROP 1 LAST PACK_TYPE 0402V
J 0
(-925 4450);
DISPLAY 0.617021 (-925 4450);
PAINT SKYBLUE (-925 4450);
FORCEPROP 1 LAST PART_NUMBER A36096-030
J 0
(-925 4500);
DISPLAY 0.617021 (-925 4500);
PAINT BLUE (-925 4500);
FORCEPROP 1 LAST TOLERANCE 10%
J 0
(-925 4600);
DISPLAY 0.617021 (-925 4600);
PAINT SKYBLUE (-925 4600);
FORCEPROP 1 LASTPIN (-975 4750) $PN 1
J 0
(-965 4730);
DISPLAY 0.617021 (-965 4730);
PAINT ORANGE (-965 4730);
FORCEPROP 1 LAST VOLTAGE 16V
J 0
(-925 4650);
DISPLAY 0.617021 (-925 4650);
PAINT SKYBLUE (-925 4650);
FORCEPROP 1 LAST VALUE 0.1UF
J 0
(-925 4700);
DISPLAY 0.617021 (-925 4700);
PAINT SKYBLUE (-925 4700);
FORCEPROP 1 LAST LOCATION C1M29
J 0
(-925 4750);
DISPLAY 0.617021 (-925 4750);
PAINT AQUA (-925 4750);
FORCEPROP 2 LAST CDS_LIB dev_discrete
J 0
(-975 4650);
PAINT ORANGE (-975 4650);
DISPLAY INVISIBLE (-975 4650);
FORCEPROP 1 LAST PATH I147
J 0
(-925 4800);
DISPLAY 0.978723 (-925 4800);
PAINT WHITE (-925 4800);
DISPLAY INVISIBLE (-925 4800);
FORCEPROP 2 LAST $SEC 1
J 0
(-925 4850);
PAINT MONO (-925 4850);
DISPLAY INVISIBLE (-925 4850);
FORCEPROP 2 LAST CDS_SEC 1
J 0
(-925 4850);
PAINT MONO (-925 4850);
DISPLAY INVISIBLE (-925 4850);
FORCEPROP 2 LAST ROOM DEBUG
J 0
(-925 4850);
DISPLAY 1.021277 (-925 4850);
PAINT ORANGE (-925 4850);
DISPLAY INVISIBLE (-925 4850);
FORCEADD OFFPAGE..5
(-3000 3525);
FORCEPROP 2 LAST $XR0 113 
J 0
(-3285 3525);
DISPLAY 0.638298 (-3285 3525);
PAINT MONO (-3285 3525);
FORCEPROP 2 LAST CDS_LIB mstr_standard
J 0
(-3000 3525);
PAINT MONO (-3000 3525);
DISPLAY INVISIBLE (-3000 3525);
FORCEPROP 1 LAST OFFPAGE TRUE
J 0
(-2675 3400);
DISPLAY 0.872340 (-2675 3400);
PAINT GREEN (-2675 3400);
DISPLAY INVISIBLE (-2675 3400);
FORCEPROP 1 LAST COMMENT_BODY TRUE
J 0
(-2900 3450);
DISPLAY 0.872340 (-2900 3450);
PAINT GREEN (-2900 3450);
DISPLAY INVISIBLE (-2900 3450);
FORCEPROP 2 LAST PATH I153
J 0
(-2950 3600);
DISPLAY 1.021277 (-2950 3600);
PAINT ORANGE (-2950 3600);
DISPLAY INVISIBLE (-2950 3600);
FORCEADD OFFPAGE..4
(-1050 3575);
FORCEPROP 2 LAST $XR0 63 
J 0
(-864 3575);
DISPLAY 0.638298 (-864 3575);
PAINT MONO (-864 3575);
FORCEPROP 1 LAST COMMENT_BODY TRUE
J 0
(-1075 3475);
DISPLAY 0.872340 (-1075 3475);
PAINT GREEN (-1075 3475);
DISPLAY INVISIBLE (-1075 3475);
FORCEPROP 2 LAST CDS_LIB mstr_standard
J 0
(-1050 3575);
PAINT MONO (-1050 3575);
DISPLAY INVISIBLE (-1050 3575);
FORCEPROP 1 LAST OFFPAGE TRUE
J 0
(-725 3450);
DISPLAY 0.872340 (-725 3450);
PAINT GREEN (-725 3450);
DISPLAY INVISIBLE (-725 3450);
FORCEPROP 2 LAST PATH I154
J 0
(-875 3650);
DISPLAY 1.021277 (-875 3650);
PAINT ORANGE (-875 3650);
DISPLAY INVISIBLE (-875 3650);
FORCEADD OFFPAGE..4
(-1050 3475);
FORCEPROP 2 LAST $XR0 29 
J 0
(-864 3475);
DISPLAY 0.638298 (-864 3475);
PAINT MONO (-864 3475);
FORCEPROP 2 LAST $XR1 113 
J 0
(-774 3475);
DISPLAY 0.638298 (-774 3475);
PAINT MONO (-774 3475);
FORCEPROP 1 LAST COMMENT_BODY TRUE
J 0
(-1075 3375);
DISPLAY 0.872340 (-1075 3375);
PAINT GREEN (-1075 3375);
DISPLAY INVISIBLE (-1075 3375);
FORCEPROP 2 LAST CDS_LIB mstr_standard
J 0
(-1050 3475);
PAINT MONO (-1050 3475);
DISPLAY INVISIBLE (-1050 3475);
FORCEPROP 1 LAST OFFPAGE TRUE
J 0
(-725 3350);
DISPLAY 0.872340 (-725 3350);
PAINT GREEN (-725 3350);
DISPLAY INVISIBLE (-725 3350);
FORCEPROP 2 LAST PATH I155
J 0
(-875 3550);
DISPLAY 1.021277 (-875 3550);
PAINT ORANGE (-875 3550);
DISPLAY INVISIBLE (-875 3550);
FORCEADD P3V3_STBY..1
(-1250 3300);
FORCEPROP 3 LASTPIN (-1250 3250) SIG_NAME P3V3_STBY\g
J 0
(-1240 3260);
DISPLAY 0.659574 (-1240 3260);
PAINT MONO (-1240 3260);
DISPLAY INVISIBLE (-1240 3260);
FORCEPROP 1 LAST HDL_POWER P3V3_STBY
J 0
(-1550 3175);
DISPLAY 0.872340 (-1550 3175);
PAINT ORANGE (-1550 3175);
DISPLAY INVISIBLE (-1550 3175);
FORCEPROP 1 LAST BODY_TYPE PLUMBING
J 0
(-1295 3257);
DISPLAY 0.340426 (-1295 3257);
PAINT GREEN (-1295 3257);
DISPLAY INVISIBLE (-1295 3257);
FORCEPROP 1 LAST VOLTAGE 3.3V
J 0
(-1295 3257);
DISPLAY 0.340426 (-1295 3257);
PAINT SKYBLUE (-1295 3257);
DISPLAY INVISIBLE (-1295 3257);
FORCEPROP 1 LAST PATH I160
J 0
(-1205 3302);
DISPLAY 0.340426 (-1205 3302);
PAINT GREEN (-1205 3302);
DISPLAY INVISIBLE (-1205 3302);
FORCEPROP 1 LAST SIZE 1B
J 0
(-1205 3322);
DISPLAY 0.340426 (-1205 3322);
PAINT GREEN (-1205 3322);
DISPLAY INVISIBLE (-1205 3322);
FORCEPROP 2 LAST CDS_LIB mstr_symbols
J 0
(-1250 3300);
PAINT ORANGE (-1250 3300);
DISPLAY INVISIBLE (-1250 3300);
FORCEADD P3V3_STBY..1
(-2250 1450);
FORCEPROP 3 LASTPIN (-2250 1400) SIG_NAME P3V3_STBY\g
J 0
(-2240 1410);
DISPLAY 0.659574 (-2240 1410);
PAINT MONO (-2240 1410);
DISPLAY INVISIBLE (-2240 1410);
FORCEPROP 1 LAST HDL_POWER P3V3_STBY
J 0
(-2550 1325);
DISPLAY 0.872340 (-2550 1325);
PAINT ORANGE (-2550 1325);
DISPLAY INVISIBLE (-2550 1325);
FORCEPROP 1 LAST BODY_TYPE PLUMBING
J 0
(-2295 1407);
DISPLAY 0.340426 (-2295 1407);
PAINT GREEN (-2295 1407);
DISPLAY INVISIBLE (-2295 1407);
FORCEPROP 1 LAST VOLTAGE 3.3V
J 0
(-2295 1407);
DISPLAY 0.340426 (-2295 1407);
PAINT SKYBLUE (-2295 1407);
DISPLAY INVISIBLE (-2295 1407);
FORCEPROP 1 LAST PATH I161
J 0
(-2205 1452);
DISPLAY 0.340426 (-2205 1452);
PAINT GREEN (-2205 1452);
DISPLAY INVISIBLE (-2205 1452);
FORCEPROP 2 LAST CDS_LIB mstr_symbols
J 0
(-2250 1450);
PAINT ORANGE (-2250 1450);
DISPLAY INVISIBLE (-2250 1450);
FORCEPROP 1 LAST SIZE 1B
J 0
(-2205 1472);
DISPLAY 0.340426 (-2205 1472);
PAINT GREEN (-2205 1472);
DISPLAY INVISIBLE (-2205 1472);
FORCEADD OFFPAGE..1
(-3125 4425);
FORCEPROP 2 LAST $XR0 113 
J 0
(-3377 4425);
DISPLAY 0.638298 (-3377 4425);
PAINT MONO (-3377 4425);
FORCEPROP 2 LAST PATH I162
J 0
(-3375 4475);
DISPLAY 1.021277 (-3375 4475);
PAINT ORANGE (-3375 4475);
DISPLAY INVISIBLE (-3375 4475);
FORCEPROP 2 LAST CDS_LIB mstr_standard
J 0
(-3125 4425);
PAINT MONO (-3125 4425);
DISPLAY INVISIBLE (-3125 4425);
FORCEPROP 1 LAST COMMENT_BODY TRUE
J 0
(-3000 4325);
DISPLAY 0.872340 (-3000 4325);
PAINT GREEN (-3000 4325);
DISPLAY INVISIBLE (-3000 4325);
FORCEPROP 1 LAST OFFPAGE TRUE
J 0
(-2800 4300);
DISPLAY 0.872340 (-2800 4300);
PAINT GREEN (-2800 4300);
DISPLAY INVISIBLE (-2800 4300);
FORCEADD OFFPAGE..5
(-3125 3975);
FORCEPROP 2 LAST $XR0 113 
J 0
(-3380 3975);
DISPLAY 0.638298 (-3380 3975);
PAINT MONO (-3380 3975);
FORCEPROP 2 LAST PATH I163
J 0
(-3375 4025);
DISPLAY 1.021277 (-3375 4025);
PAINT ORANGE (-3375 4025);
DISPLAY INVISIBLE (-3375 4025);
FORCEPROP 2 LAST CDS_LIB mstr_standard
J 0
(-3125 3975);
PAINT MONO (-3125 3975);
DISPLAY INVISIBLE (-3125 3975);
FORCEPROP 1 LAST OFFPAGE TRUE
J 0
(-2800 3850);
DISPLAY 0.872340 (-2800 3850);
PAINT GREEN (-2800 3850);
DISPLAY INVISIBLE (-2800 3850);
FORCEPROP 1 LAST COMMENT_BODY TRUE
J 0
(-3025 3900);
DISPLAY 0.872340 (-3025 3900);
PAINT GREEN (-3025 3900);
DISPLAY INVISIBLE (-3025 3900);
FORCEADD RES..1
(-2600 4150);
FORCEPROP 1 LAST PACK_TYPE 0402
J 0
(-2725 4050);
DISPLAY 0.617021 (-2725 4050);
PAINT SKYBLUE (-2725 4050);
FORCEPROP 1 LAST PART_NUMBER G21796-026
J 0
(-2625 4050);
DISPLAY 0.617021 (-2625 4050);
PAINT BLUE (-2625 4050);
FORCEPROP 1 LAST VALUE 1.00K
J 2
(-2725 4100);
DISPLAY 0.617021 (-2725 4100);
PAINT SKYBLUE (-2725 4100);
FORCEPROP 1 LAST TOLERANCE 1%
J 0
(-2700 4100);
DISPLAY 0.617021 (-2700 4100);
PAINT SKYBLUE (-2700 4100);
FORCEPROP 1 LASTPIN (-2700 4150) $PN 1
J 0
(-2688 4162);
DISPLAY 0.617021 (-2688 4162);
PAINT ORANGE (-2688 4162);
FORCEPROP 1 LAST WATTAGE 1/16W
J 2
(-2500 4100);
DISPLAY 0.617021 (-2500 4100);
PAINT SKYBLUE (-2500 4100);
FORCEPROP 1 LAST LOCATION R9B14
J 0
(-2650 4200);
DISPLAY 0.617021 (-2650 4200);
PAINT AQUA (-2650 4200);
FORCEPROP 1 LAST MATERIAL CHIP
J 0
(-2475 4100);
DISPLAY 0.617021 (-2475 4100);
PAINT SKYBLUE (-2475 4100);
FORCEPROP 1 LASTPIN (-2500 4150) $PN 2
J 0
(-2538 4162);
DISPLAY 0.617021 (-2538 4162);
PAINT ORANGE (-2538 4162);
FORCEPROP 2 LAST CDS_LIB mstr_discrete
J 0
(-2600 4150);
PAINT ORANGE (-2600 4150);
DISPLAY INVISIBLE (-2600 4150);
FORCEPROP 1 LAST PATH I168
J 0
(-2650 4300);
DISPLAY 0.978723 (-2650 4300);
PAINT WHITE (-2650 4300);
DISPLAY INVISIBLE (-2650 4300);
FORCEPROP 2 LAST SEC 1
J 0
(-2650 4350);
DISPLAY 0.680851 (-2650 4350);
PAINT MONO (-2650 4350);
DISPLAY INVISIBLE (-2650 4350);
FORCEPROP 2 LAST SEC_TYPE 0402
J 0
(-2650 4350);
DISPLAY 1.021277 (-2650 4350);
PAINT ORANGE (-2650 4350);
DISPLAY INVISIBLE (-2650 4350);
FORCEPROP 2 LAST ROOM DEBUG
J 0
(-2555 4315);
DISPLAY 1.276596 (-2555 4315);
PAINT WHITE (-2555 4315);
DISPLAY INVISIBLE (-2555 4315);
FORCEADD OFFPAGE..1
(-3125 4150);
FORCEPROP 2 LAST $XR0 96 
J 0
(-3346 4150);
DISPLAY 0.638298 (-3346 4150);
PAINT MONO (-3346 4150);
FORCEPROP 2 LAST $XR1 21 
J 0
(-3436 4150);
DISPLAY 0.638298 (-3436 4150);
PAINT MONO (-3436 4150);
FORCEPROP 1 LAST OFFPAGE TRUE
J 0
(-2800 4025);
DISPLAY 0.872340 (-2800 4025);
PAINT GREEN (-2800 4025);
DISPLAY INVISIBLE (-2800 4025);
FORCEPROP 1 LAST COMMENT_BODY TRUE
J 0
(-3000 4050);
DISPLAY 0.872340 (-3000 4050);
PAINT GREEN (-3000 4050);
DISPLAY INVISIBLE (-3000 4050);
FORCEPROP 2 LAST PATH I169
J 0
(-3075 4225);
DISPLAY 1.021277 (-3075 4225);
PAINT ORANGE (-3075 4225);
DISPLAY INVISIBLE (-3075 4225);
FORCEPROP 2 LAST CDS_LIB mstr_standard
J 0
(-3125 4150);
PAINT ORANGE (-3125 4150);
DISPLAY INVISIBLE (-3125 4150);
FORCEADD VCC_CORE..1
(-1100 4900);
FORCEPROP 3 LASTPIN (-1100 4850) SIG_NAME P1V8_MCP_CPU0\g
J 0
(-1090 4860);
DISPLAY 0.659574 (-1090 4860);
PAINT MONO (-1090 4860);
DISPLAY INVISIBLE (-1090 4860);
FORCEPROP 1 LAST HDL_POWER P1V8_MCP_CPU0
J 1
(-1100 4950);
DISPLAY 0.617021 (-1100 4950);
PAINT GREEN (-1100 4950);
FORCEPROP 1 LAST PATH I171
J 0
(-1050 4925);
DISPLAY 0.872340 (-1050 4925);
PAINT AQUA (-1050 4925);
DISPLAY INVISIBLE (-1050 4925);
FORCEPROP 2 LAST CDS_LIB mstr_symbols
J 0
(-1100 4900);
PAINT ORANGE (-1100 4900);
DISPLAY INVISIBLE (-1100 4900);
FORCEADD OFFPAGE..1
(950 4400);
FORCEPROP 2 LAST $XR0 113 
J 0
(668 4400);
DISPLAY 0.638298 (668 4400);
PAINT MONO (668 4400);
FORCEPROP 2 LAST $XR1 29 
J 0
(578 4400);
DISPLAY 0.638298 (578 4400);
PAINT MONO (578 4400);
FORCEPROP 2 LAST $XR2 63 
J 0
(488 4400);
DISPLAY 0.638298 (488 4400);
PAINT MONO (488 4400);
FORCEPROP 2 LAST PATH I172
J 0
(700 4450);
DISPLAY 1.021277 (700 4450);
PAINT ORANGE (700 4450);
DISPLAY INVISIBLE (700 4450);
FORCEPROP 2 LAST CDS_LIB mstr_standard
J 0
(950 4400);
PAINT MONO (950 4400);
DISPLAY INVISIBLE (950 4400);
FORCEPROP 1 LAST COMMENT_BODY TRUE
J 0
(1075 4300);
DISPLAY 1.404255 (1075 4300);
PAINT PEACH (1075 4300);
DISPLAY INVISIBLE (1075 4300);
FORCEPROP 1 LAST OFFPAGE TRUE
J 0
(1275 4275);
DISPLAY 1.404255 (1275 4275);
PAINT GREEN (1275 4275);
DISPLAY INVISIBLE (1275 4275);
FORCEADD SCONN10_C12536004..1
(-1375 4375);
FORCEPROP 2 LASTPIN (-1525 4475) $PN 1
J 2
(-1535 4485);
DISPLAY 0.617021 (-1535 4485);
PAINT ORANGE (-1535 4485);
FORCEPROP 2 LASTPIN (-1525 4425) $PN 3
J 2
(-1535 4435);
DISPLAY 0.617021 (-1535 4435);
PAINT ORANGE (-1535 4435);
FORCEPROP 2 LASTPIN (-1525 4375) $PN 5
J 2
(-1535 4385);
DISPLAY 0.617021 (-1535 4385);
PAINT ORANGE (-1535 4385);
FORCEPROP 2 LASTPIN (-1525 4325) $PN 7
J 2
(-1535 4335);
DISPLAY 0.617021 (-1535 4335);
PAINT ORANGE (-1535 4335);
FORCEPROP 2 LASTPIN (-1525 4275) $PN 9
J 2
(-1535 4285);
DISPLAY 0.617021 (-1535 4285);
PAINT ORANGE (-1535 4285);
FORCEPROP 1 LAST PART_NUMBER C12536-004
J 0
(-1475 4150);
DISPLAY 0.617021 (-1475 4150);
PAINT BLUE (-1475 4150);
FORCEPROP 2 LASTPIN (-1225 4275) $PN 10
J 0
(-1215 4285);
DISPLAY 0.617021 (-1215 4285);
PAINT ORANGE (-1215 4285);
FORCEPROP 2 LASTPIN (-1225 4325) $PN 8
J 0
(-1215 4335);
DISPLAY 0.617021 (-1215 4335);
PAINT ORANGE (-1215 4335);
FORCEPROP 2 LASTPIN (-1225 4375) $PN 6
J 0
(-1215 4385);
DISPLAY 0.617021 (-1215 4385);
PAINT ORANGE (-1215 4385);
FORCEPROP 2 LASTPIN (-1225 4425) $PN 4
J 0
(-1215 4435);
DISPLAY 0.617021 (-1215 4435);
PAINT ORANGE (-1215 4435);
FORCEPROP 2 LASTPIN (-1225 4475) $PN 2
J 0
(-1215 4485);
DISPLAY 0.617021 (-1215 4485);
PAINT ORANGE (-1215 4485);
FORCEPROP 1 LAST MATERIAL CONN
J 0
(-1475 4600);
DISPLAY 0.617021 (-1475 4600);
PAINT SKYBLUE (-1475 4600);
FORCEPROP 1 LAST LOCATION J9B4
J 0
(-1475 4650);
DISPLAY 0.617021 (-1475 4650);
PAINT AQUA (-1475 4650);
FORCEPROP 2 LAST ROOM DEBUG
J 0
(-1625 4800);
DISPLAY 1.021277 (-1625 4800);
PAINT ORANGE (-1625 4800);
DISPLAY INVISIBLE (-1625 4800);
FORCEPROP 2 LAST SEC 1
J 0
(-1625 4750);
DISPLAY 0.680851 (-1625 4750);
PAINT MONO (-1625 4750);
DISPLAY INVISIBLE (-1625 4750);
FORCEPROP 2 LAST SEC_TYPE SMLF
J 0
(-1625 4750);
DISPLAY 1.021277 (-1625 4750);
PAINT ORANGE (-1625 4750);
DISPLAY INVISIBLE (-1625 4750);
FORCEPROP 1 LAST PACK_TYPE SMLF
J 0
(-1475 4100);
DISPLAY 0.978723 (-1475 4100);
PAINT SKYBLUE (-1475 4100);
DISPLAY INVISIBLE (-1475 4100);
FORCEPROP 2 LAST CDS_LIB mstr_sconn
J 0
(-1375 4375);
PAINT ORANGE (-1375 4375);
DISPLAY INVISIBLE (-1375 4375);
FORCEPROP 1 LAST PATH I175
J 0
(-1025 4600);
DISPLAY 0.936170 (-1025 4600);
PAINT GREEN (-1025 4600);
DISPLAY INVISIBLE (-1025 4600);
FORCEADD OFFPAGE..2
(-550 4375);
FORCEPROP 2 LAST $XR0 29 
J 0
(-361 4375);
DISPLAY 0.638298 (-361 4375);
PAINT MONO (-361 4375);
FORCEPROP 2 LAST $XR1 63 
J 0
(-271 4375);
DISPLAY 0.638298 (-271 4375);
PAINT MONO (-271 4375);
FORCEPROP 2 LAST $XR2 113 
J 0
(-181 4375);
DISPLAY 0.638298 (-181 4375);
PAINT MONO (-181 4375);
FORCEPROP 1 LAST COMMENT_BODY TRUE
J 0
(-595 4280);
DISPLAY 0.872340 (-595 4280);
PAINT GREEN (-595 4280);
DISPLAY INVISIBLE (-595 4280);
FORCEPROP 2 LAST CDS_LIB mstr_standard
J 0
(-550 4375);
PAINT MONO (-550 4375);
DISPLAY INVISIBLE (-550 4375);
FORCEPROP 2 LAST PATH I176
J 0
(-175 4425);
DISPLAY 1.021277 (-175 4425);
PAINT ORANGE (-175 4425);
DISPLAY INVISIBLE (-175 4425);
FORCEPROP 1 LAST OFFPAGE TRUE
J 0
(-225 4250);
DISPLAY 0.872340 (-225 4250);
PAINT GREEN (-225 4250);
DISPLAY INVISIBLE (-225 4250);
FORCEADD RES..2
R 2
(2600 4150);
FORCEPROP 1 LAST PACK_TYPE 0402
J 2
(2560 3975);
DISPLAY 0.617021 (2560 3975);
PAINT SKYBLUE (2560 3975);
FORCEPROP 1 LAST PART_NUMBER G21796-026
J 2
(2560 4025);
DISPLAY 0.617021 (2560 4025);
PAINT BLUE (2560 4025);
FORCEPROP 1 LASTPIN (2600 4050) $PN 2
J 2
(2595 4060);
DISPLAY 0.617021 (2595 4060);
PAINT ORANGE (2595 4060);
FORCEPROP 1 LAST MATERIAL CHIP
J 2
(2560 4075);
DISPLAY 0.617021 (2560 4075);
PAINT SKYBLUE (2560 4075);
FORCEPROP 1 LAST TOLERANCE 1%
J 2
(2555 4175);
DISPLAY 0.617021 (2555 4175);
PAINT SKYBLUE (2555 4175);
FORCEPROP 1 LAST VALUE 1.00K
J 2
(2555 4225);
DISPLAY 0.617021 (2555 4225);
PAINT SKYBLUE (2555 4225);
FORCEPROP 1 LAST LOCATION R9B9
J 2
(2555 4275);
DISPLAY 0.617021 (2555 4275);
PAINT AQUA (2555 4275);
FORCEPROP 1 LAST WATTAGE 1/16W
J 2
(2560 4125);
DISPLAY 0.617021 (2560 4125);
PAINT SKYBLUE (2560 4125);
FORCEPROP 1 LASTPIN (2600 4250) $PN 1
J 2
(2595 4212);
DISPLAY 0.617021 (2595 4212);
PAINT ORANGE (2595 4212);
FORCEPROP 1 LAST PATH I179
J 2
(2550 4325);
DISPLAY 0.978723 (2550 4325);
PAINT WHITE (2550 4325);
DISPLAY INVISIBLE (2550 4325);
FORCEPROP 2 LAST SEC 1
J 2
(2550 4375);
DISPLAY 0.680851 (2550 4375);
PAINT MONO (2550 4375);
DISPLAY INVISIBLE (2550 4375);
FORCEPROP 2 LAST SEC_TYPE 0402
J 2
(2550 4375);
DISPLAY 1.021277 (2550 4375);
PAINT ORANGE (2550 4375);
DISPLAY INVISIBLE (2550 4375);
FORCEPROP 2 LAST CDS_LIB mstr_discrete
J 2
(2600 4150);
PAINT ORANGE (2600 4150);
DISPLAY INVISIBLE (2600 4150);
FORCEADD RES..1
(2800 4400);
FORCEPROP 1 LAST WATTAGE 1/16W
J 2
(2775 4250);
DISPLAY 0.617021 (2775 4250);
PAINT SKYBLUE (2775 4250);
FORCEPROP 1 LAST VALUE 49.9
J 2
(2775 4300);
DISPLAY 0.617021 (2775 4300);
PAINT SKYBLUE (2775 4300);
FORCEPROP 1 LASTPIN (2700 4400) $PN 1
J 0
(2712 4412);
DISPLAY 0.617021 (2712 4412);
PAINT ORANGE (2712 4412);
FORCEPROP 1 LAST MATERIAL CHIP
J 0
(2800 4250);
DISPLAY 0.617021 (2800 4250);
PAINT SKYBLUE (2800 4250);
FORCEPROP 1 LAST TOLERANCE 1%
J 0
(2800 4300);
DISPLAY 0.617021 (2800 4300);
PAINT SKYBLUE (2800 4300);
FORCEPROP 1 LAST PART_NUMBER G21796-047
J 0
(2750 4500);
DISPLAY 0.617021 (2750 4500);
PAINT BLUE (2750 4500);
FORCEPROP 1 LAST LOCATION R9B10
J 0
(2750 4450);
DISPLAY 0.617021 (2750 4450);
PAINT AQUA (2750 4450);
FORCEPROP 1 LASTPIN (2900 4400) $PN 2
J 0
(2862 4412);
DISPLAY 0.617021 (2862 4412);
PAINT ORANGE (2862 4412);
FORCEPROP 1 LAST PACK_TYPE 0402
J 0
(2875 4300);
DISPLAY 0.617021 (2875 4300);
PAINT SKYBLUE (2875 4300);
FORCEPROP 2 LAST CDS_LIB mstr_discrete
J 0
(2800 4400);
PAINT ORANGE (2800 4400);
DISPLAY INVISIBLE (2800 4400);
FORCEPROP 1 LAST PATH I180
J 0
(2750 4550);
DISPLAY 0.978723 (2750 4550);
PAINT WHITE (2750 4550);
DISPLAY INVISIBLE (2750 4550);
FORCEPROP 2 LAST ROOM DEBUG
J 0
(2850 4575);
DISPLAY 1.617021 (2850 4575);
PAINT WHITE (2850 4575);
DISPLAY INVISIBLE (2850 4575);
FORCEPROP 2 LAST SEC 1
J 0
(2750 4600);
DISPLAY 0.680851 (2750 4600);
PAINT MONO (2750 4600);
DISPLAY INVISIBLE (2750 4600);
FORCEPROP 2 LAST SEC_TYPE 0402
J 0
(2750 4600);
DISPLAY 1.021277 (2750 4600);
PAINT ORANGE (2750 4600);
DISPLAY INVISIBLE (2750 4600);
FORCEPROP 2 LAST BOM_COST DEBUG
J 0
(2850 4575);
DISPLAY 1.617021 (2850 4575);
PAINT WHITE (2850 4575);
DISPLAY INVISIBLE (2850 4575);
FORCEADD GND..1
(2600 3950);
FORCEPROP 3 LASTPIN (2600 4000) SIG_NAME GND\g
J 0
(2610 4010);
DISPLAY 0.659574 (2610 4010);
PAINT MONO (2610 4010);
DISPLAY INVISIBLE (2610 4010);
FORCEPROP 1 LAST BODY_TYPE PLUMBING
J 0
(2555 3907);
DISPLAY 0.340426 (2555 3907);
PAINT GREEN (2555 3907);
DISPLAY INVISIBLE (2555 3907);
FORCEPROP 1 LAST VOLTAGE 0.0V
J 0
(2555 3907);
DISPLAY 0.340426 (2555 3907);
PAINT SKYBLUE (2555 3907);
DISPLAY INVISIBLE (2555 3907);
FORCEPROP 1 LAST SIZE 1B
J 0
(2675 3900);
DISPLAY 2.382979 (2675 3900);
PAINT GREEN (2675 3900);
DISPLAY INVISIBLE (2675 3900);
FORCEPROP 2 LAST CDS_LIB mstr_symbols
J 0
(2600 3950);
PAINT ORANGE (2600 3950);
DISPLAY INVISIBLE (2600 3950);
FORCEPROP 1 LAST PATH I182
J 0
(2675 3950);
DISPLAY 0.872340 (2675 3950);
PAINT AQUA (2675 3950);
DISPLAY INVISIBLE (2675 3950);
FORCEPROP 1 LAST HDL_POWER GND
J 0
(2600 4100);
PAINT GREEN (2600 4100);
DISPLAY INVISIBLE (2600 4100);
FORCEADD 74CBTLV1G125..1
(3575 4400);
FORCEPROP 2 LASTPIN (3325 4400) $PN 2
J 2
(3315 4410);
DISPLAY 0.617021 (3315 4410);
PAINT ORANGE (3315 4410);
FORCEPROP 2 LASTPIN (3325 4350) $PN 1
J 2
(3315 4360);
DISPLAY 0.617021 (3315 4360);
PAINT ORANGE (3315 4360);
FORCEPROP 1 LAST LOCATION U9A5
J 0
(3409 4531);
DISPLAY 0.617021 (3409 4531);
PAINT AQUA (3409 4531);
FORCEPROP 1 LAST PACK_TYPE SMLF
J 0
(3400 4570);
DISPLAY 0.617021 (3400 4570);
PAINT SKYBLUE (3400 4570);
FORCEPROP 1 LAST MATERIAL IC
J 0
(3400 4620);
DISPLAY 0.617021 (3400 4620);
PAINT SKYBLUE (3400 4620);
FORCEPROP 1 LAST PART_NUMBER C88177-001
J 0
(3410 4260);
DISPLAY 0.617021 (3410 4260);
PAINT BLUE (3410 4260);
FORCEPROP 2 LASTPIN (3825 4400) $PN 4
J 0
(3835 4410);
DISPLAY 0.617021 (3835 4410);
PAINT ORANGE (3835 4410);
FORCEPROP 1 LAST POWER_GROUP VCC=P3V3_STBY;GND=GND;
J 0
(3350 4200);
DISPLAY 0.617021 (3350 4200);
PAINT ORANGE (3350 4200);
FORCEPROP 2 LAST CDS_LIB mstr_ttl
J 0
(3575 4400);
PAINT ORANGE (3575 4400);
DISPLAY INVISIBLE (3575 4400);
FORCEPROP 2 LAST ROOM DEBUG
J 0
(3400 4725);
DISPLAY 1.021277 (3400 4725);
PAINT ORANGE (3400 4725);
DISPLAY INVISIBLE (3400 4725);
FORCEPROP 2 LAST SEC_TYPE SMLF
J 0
(3400 4650);
DISPLAY 1.021277 (3400 4650);
PAINT ORANGE (3400 4650);
DISPLAY INVISIBLE (3400 4650);
FORCEPROP 2 LAST BOM_COST DEBUG
J 0
(3400 4725);
DISPLAY 1.021277 (3400 4725);
PAINT ORANGE (3400 4725);
DISPLAY INVISIBLE (3400 4725);
FORCEPROP 2 LAST SEC 1
J 0
(3400 4650);
DISPLAY 0.680851 (3400 4650);
PAINT MONO (3400 4650);
DISPLAY INVISIBLE (3400 4650);
FORCEPROP 1 LAST PATH I185
J 0
(3675 4520);
DISPLAY 0.872340 (3675 4520);
PAINT PINK (3675 4520);
DISPLAY INVISIBLE (3675 4520);
FORCEADD GND..1
(3925 4250);
FORCEPROP 3 LASTPIN (3925 4300) SIG_NAME GND\g
J 0
(3935 4310);
DISPLAY 0.659574 (3935 4310);
PAINT MONO (3935 4310);
DISPLAY INVISIBLE (3935 4310);
FORCEPROP 1 LAST VOLTAGE 0.0V
J 0
(3880 4207);
DISPLAY 0.340426 (3880 4207);
PAINT SKYBLUE (3880 4207);
DISPLAY INVISIBLE (3880 4207);
FORCEPROP 2 LAST CDS_LIB mstr_symbols
J 0
(3925 4250);
PAINT MONO (3925 4250);
DISPLAY INVISIBLE (3925 4250);
FORCEPROP 1 LAST SIZE 1B
J 0
(4000 4200);
DISPLAY 2.382979 (4000 4200);
PAINT GREEN (4000 4200);
DISPLAY INVISIBLE (4000 4200);
FORCEPROP 1 LAST BODY_TYPE PLUMBING
J 0
(3880 4207);
DISPLAY 0.340426 (3880 4207);
PAINT GREEN (3880 4207);
DISPLAY INVISIBLE (3880 4207);
FORCEPROP 1 LAST PATH I186
J 0
(4000 4250);
DISPLAY 0.872340 (4000 4250);
PAINT AQUA (4000 4250);
DISPLAY INVISIBLE (4000 4250);
FORCEPROP 1 LAST HDL_POWER GND
J 0
(3925 4400);
PAINT GREEN (3925 4400);
DISPLAY INVISIBLE (3925 4400);
FORCEADD RES..2
R 2
(2450 2075);
FORCEPROP 1 LAST MATERIAL CHIP
J 2
(2410 2000);
DISPLAY 0.617021 (2410 2000);
PAINT SKYBLUE (2410 2000);
FORCEPROP 1 LAST PART_NUMBER G21796-047
J 2
(2410 1950);
DISPLAY 0.617021 (2410 1950);
PAINT BLUE (2410 1950);
FORCEPROP 1 LASTPIN (2450 1975) $PN 2
J 2
(2445 1985);
DISPLAY 0.617021 (2445 1985);
PAINT ORANGE (2445 1985);
FORCEPROP 1 LAST WATTAGE 1/16W
J 2
(2410 2050);
DISPLAY 0.617021 (2410 2050);
PAINT SKYBLUE (2410 2050);
FORCEPROP 1 LAST VALUE 49.9
J 2
(2405 2150);
DISPLAY 0.617021 (2405 2150);
PAINT SKYBLUE (2405 2150);
FORCEPROP 1 LAST LOCATION R6M8
J 2
(2405 2200);
DISPLAY 0.617021 (2405 2200);
PAINT AQUA (2405 2200);
FORCEPROP 1 LASTPIN (2450 2175) $PN 1
J 2
(2445 2137);
DISPLAY 0.617021 (2445 2137);
PAINT ORANGE (2445 2137);
FORCEPROP 1 LAST PACK_TYPE 0402
J 2
(2410 1900);
DISPLAY 0.617021 (2410 1900);
PAINT SKYBLUE (2410 1900);
FORCEPROP 1 LAST TOLERANCE 1%
J 2
(2405 2100);
DISPLAY 0.617021 (2405 2100);
PAINT SKYBLUE (2405 2100);
FORCEPROP 2 LAST CDS_LOCATION R6M8
J 2
(2405 2200);
DISPLAY 0.617021 (2405 2200);
PAINT AQUA (2405 2200);
DISPLAY INVISIBLE (2405 2200);
FORCEPROP 1 LAST PATH I188
J 2
(2400 2250);
DISPLAY 0.978723 (2400 2250);
PAINT WHITE (2400 2250);
DISPLAY INVISIBLE (2400 2250);
FORCEPROP 2 LAST ROOM DEBUG
J 2
(2405 2240);
DISPLAY 1.276596 (2405 2240);
PAINT WHITE (2405 2240);
DISPLAY INVISIBLE (2405 2240);
FORCEPROP 2 LAST CDS_LIB mstr_discrete
J 2
(2450 2075);
PAINT ORANGE (2450 2075);
DISPLAY INVISIBLE (2450 2075);
FORCEPROP 2 LAST SEC 1
J 2
(2400 2300);
DISPLAY 0.680851 (2400 2300);
PAINT MONO (2400 2300);
DISPLAY INVISIBLE (2400 2300);
FORCEPROP 2 LAST SEC_TYPE 0402
J 2
(2400 2300);
DISPLAY 1.021277 (2400 2300);
PAINT ORANGE (2400 2300);
DISPLAY INVISIBLE (2400 2300);
FORCEADD 74CBTLV1G125..1
(1600 2250);
FORCEPROP 2 LASTPIN (1350 2200) $PN 1
J 2
(1340 2210);
DISPLAY 0.617021 (1340 2210);
PAINT ORANGE (1340 2210);
FORCEPROP 2 LASTPIN (1350 2250) $PN 2
J 2
(1340 2260);
DISPLAY 0.617021 (1340 2260);
PAINT ORANGE (1340 2260);
FORCEPROP 1 LAST MATERIAL IC
J 0
(1425 2470);
DISPLAY 0.617021 (1425 2470);
PAINT SKYBLUE (1425 2470);
FORCEPROP 1 LAST PACK_TYPE SMLF
J 0
(1425 2420);
DISPLAY 0.617021 (1425 2420);
PAINT SKYBLUE (1425 2420);
FORCEPROP 1 LAST PART_NUMBER C88177-001
J 0
(1435 2110);
DISPLAY 0.617021 (1435 2110);
PAINT BLUE (1435 2110);
FORCEPROP 1 LAST LOCATION U6M1
J 0
(1434 2381);
DISPLAY 0.617021 (1434 2381);
PAINT AQUA (1434 2381);
FORCEPROP 2 LASTPIN (1850 2250) $PN 4
J 0
(1860 2260);
DISPLAY 0.617021 (1860 2260);
PAINT ORANGE (1860 2260);
FORCEPROP 1 LAST POWER_GROUP VCC=P3V3_STBY;GND=GND;
J 0
(1375 2050);
DISPLAY 0.617021 (1375 2050);
PAINT ORANGE (1375 2050);
FORCEPROP 2 LAST SEC_TYPE SMLF
J 0
(1425 2500);
DISPLAY 1.021277 (1425 2500);
PAINT ORANGE (1425 2500);
DISPLAY INVISIBLE (1425 2500);
FORCEPROP 2 LAST SEC 1
J 0
(1425 2500);
DISPLAY 0.680851 (1425 2500);
PAINT MONO (1425 2500);
DISPLAY INVISIBLE (1425 2500);
FORCEPROP 2 LAST BOM_COST DEBUG
J 0
(1425 2575);
DISPLAY 1.021277 (1425 2575);
PAINT ORANGE (1425 2575);
DISPLAY INVISIBLE (1425 2575);
FORCEPROP 2 LAST ROOM DEBUG
J 0
(1425 2575);
DISPLAY 1.021277 (1425 2575);
PAINT ORANGE (1425 2575);
DISPLAY INVISIBLE (1425 2575);
FORCEPROP 1 LAST PATH I190
J 0
(1700 2370);
DISPLAY 0.872340 (1700 2370);
PAINT PINK (1700 2370);
DISPLAY INVISIBLE (1700 2370);
FORCEPROP 2 LAST CDS_LIB mstr_ttl
J 0
(1600 2250);
PAINT ORANGE (1600 2250);
DISPLAY INVISIBLE (1600 2250);
FORCEADD OFFPAGE..1
(575 2200);
FORCEPROP 2 LAST $XR0 55 
J 0
(354 2200);
DISPLAY 0.638298 (354 2200);
PAINT MONO (354 2200);
FORCEPROP 2 LAST $XR1 190 
J 0
(234 2200);
DISPLAY 0.638298 (234 2200);
PAINT MONO (234 2200);
FORCEPROP 2 LAST PATH I192
J 0
(625 2275);
DISPLAY 1.021277 (625 2275);
PAINT ORANGE (625 2275);
DISPLAY INVISIBLE (625 2275);
FORCEPROP 1 LAST COMMENT_BODY TRUE
J 0
(700 2100);
DISPLAY 1.404255 (700 2100);
PAINT PEACH (700 2100);
DISPLAY INVISIBLE (700 2100);
FORCEPROP 1 LAST OFFPAGE TRUE
J 0
(900 2075);
DISPLAY 1.404255 (900 2075);
PAINT GREEN (900 2075);
DISPLAY INVISIBLE (900 2075);
FORCEPROP 2 LAST CDS_LIB mstr_standard
J 0
(575 2200);
PAINT ORANGE (575 2200);
DISPLAY INVISIBLE (575 2200);
FORCEADD OFFPAGE..1
(2200 4350);
FORCEPROP 2 LAST $XR0 191 
J 0
(1948 4350);
DISPLAY 0.638298 (1948 4350);
PAINT MONO (1948 4350);
FORCEPROP 2 LAST $XR1 113 
J 0
(1828 4350);
DISPLAY 0.638298 (1828 4350);
PAINT MONO (1828 4350);
FORCEPROP 2 LAST CDS_LIB mstr_standard
J 0
(2200 4350);
PAINT ORANGE (2200 4350);
DISPLAY INVISIBLE (2200 4350);
FORCEPROP 2 LAST PATH I193
J 0
(2250 4425);
DISPLAY 1.021277 (2250 4425);
PAINT ORANGE (2250 4425);
DISPLAY INVISIBLE (2250 4425);
FORCEPROP 1 LAST COMMENT_BODY TRUE
J 0
(2325 4250);
DISPLAY 1.404255 (2325 4250);
PAINT PEACH (2325 4250);
DISPLAY INVISIBLE (2325 4250);
FORCEPROP 1 LAST OFFPAGE TRUE
J 0
(2525 4225);
DISPLAY 1.404255 (2525 4225);
PAINT GREEN (2525 4225);
DISPLAY INVISIBLE (2525 4225);
FORCEADD RES..2
R 2
(2450 2650);
FORCEPROP 1 LAST PACK_TYPE 0402
J 2
(2410 2475);
DISPLAY 0.617021 (2410 2475);
PAINT SKYBLUE (2410 2475);
FORCEPROP 1 LAST PART_NUMBER G21796-047
J 2
(2410 2525);
DISPLAY 0.617021 (2410 2525);
PAINT BLUE (2410 2525);
FORCEPROP 1 LASTPIN (2450 2550) $PN 2
J 2
(2445 2560);
DISPLAY 0.617021 (2445 2560);
PAINT ORANGE (2445 2560);
FORCEPROP 1 LAST WATTAGE 1/16W
J 2
(2410 2625);
DISPLAY 0.617021 (2410 2625);
PAINT SKYBLUE (2410 2625);
FORCEPROP 1 LAST MATERIAL CHIP
J 2
(2410 2575);
DISPLAY 0.617021 (2410 2575);
PAINT SKYBLUE (2410 2575);
FORCEPROP 1 LAST VALUE 49.9
J 2
(2405 2725);
DISPLAY 0.617021 (2405 2725);
PAINT SKYBLUE (2405 2725);
FORCEPROP 1 LAST LOCATION R1M22
J 2
(2405 2775);
DISPLAY 0.617021 (2405 2775);
PAINT AQUA (2405 2775);
FORCEPROP 1 LASTPIN (2450 2750) $PN 1
J 2
(2445 2712);
DISPLAY 0.617021 (2445 2712);
PAINT ORANGE (2445 2712);
FORCEPROP 1 LAST TOLERANCE 1%
J 2
(2405 2675);
DISPLAY 0.617021 (2405 2675);
PAINT SKYBLUE (2405 2675);
FORCEPROP 2 LAST CDS_LIB mstr_discrete
J 2
(2450 2650);
PAINT ORANGE (2450 2650);
DISPLAY INVISIBLE (2450 2650);
FORCEPROP 2 LAST ROOM DEBUG
J 2
(2405 2815);
DISPLAY 1.276596 (2405 2815);
PAINT WHITE (2405 2815);
DISPLAY INVISIBLE (2405 2815);
FORCEPROP 2 LAST SEC 1
J 2
(2400 2875);
DISPLAY 0.680851 (2400 2875);
PAINT MONO (2400 2875);
DISPLAY INVISIBLE (2400 2875);
FORCEPROP 1 LAST PATH I195
J 2
(2400 2825);
DISPLAY 0.978723 (2400 2825);
PAINT WHITE (2400 2825);
DISPLAY INVISIBLE (2400 2825);
FORCEPROP 2 LAST SEC_TYPE 0402
J 2
(2400 2875);
DISPLAY 1.021277 (2400 2875);
PAINT ORANGE (2400 2875);
DISPLAY INVISIBLE (2400 2875);
FORCEADD 74CBTLV1G125..1
(1600 2825);
FORCEPROP 2 LASTPIN (1350 2775) $PN 1
J 2
(1340 2785);
DISPLAY 0.617021 (1340 2785);
PAINT ORANGE (1340 2785);
FORCEPROP 1 LAST MATERIAL IC
J 0
(1425 3045);
DISPLAY 0.617021 (1425 3045);
PAINT SKYBLUE (1425 3045);
FORCEPROP 2 LASTPIN (1350 2825) $PN 2
J 2
(1340 2835);
DISPLAY 0.617021 (1340 2835);
PAINT ORANGE (1340 2835);
FORCEPROP 1 LAST PACK_TYPE SMLF
J 0
(1425 2995);
DISPLAY 0.617021 (1425 2995);
PAINT SKYBLUE (1425 2995);
FORCEPROP 1 LAST PART_NUMBER C88177-001
J 0
(1435 2685);
DISPLAY 0.617021 (1435 2685);
PAINT BLUE (1435 2685);
FORCEPROP 1 LAST LOCATION U1M5
J 0
(1434 2956);
DISPLAY 0.617021 (1434 2956);
PAINT AQUA (1434 2956);
FORCEPROP 1 LAST POWER_GROUP VCC=P3V3_STBY;GND=GND;
J 0
(1375 2625);
DISPLAY 0.617021 (1375 2625);
PAINT ORANGE (1375 2625);
FORCEPROP 2 LASTPIN (1850 2825) $PN 4
J 0
(1860 2835);
DISPLAY 0.617021 (1860 2835);
PAINT ORANGE (1860 2835);
FORCEPROP 2 LAST CDS_LIB mstr_ttl
J 0
(1600 2825);
PAINT ORANGE (1600 2825);
DISPLAY INVISIBLE (1600 2825);
FORCEPROP 1 LAST PATH I196
J 0
(1700 2945);
DISPLAY 0.872340 (1700 2945);
PAINT PINK (1700 2945);
DISPLAY INVISIBLE (1700 2945);
FORCEPROP 2 LAST SEC_TYPE SMLF
J 0
(1425 3075);
DISPLAY 1.021277 (1425 3075);
PAINT ORANGE (1425 3075);
DISPLAY INVISIBLE (1425 3075);
FORCEPROP 2 LAST BOM_COST DEBUG
J 0
(1425 3150);
DISPLAY 1.021277 (1425 3150);
PAINT ORANGE (1425 3150);
DISPLAY INVISIBLE (1425 3150);
FORCEPROP 2 LAST SEC 1
J 0
(1425 3075);
DISPLAY 0.680851 (1425 3075);
PAINT MONO (1425 3075);
DISPLAY INVISIBLE (1425 3075);
FORCEPROP 2 LAST ROOM DEBUG
J 0
(1425 3150);
DISPLAY 1.021277 (1425 3150);
PAINT ORANGE (1425 3150);
DISPLAY INVISIBLE (1425 3150);
FORCEADD OFFPAGE..1
(575 2775);
FORCEPROP 2 LAST $XR0 191 
J 0
(323 2775);
DISPLAY 0.638298 (323 2775);
PAINT MONO (323 2775);
FORCEPROP 2 LAST $XR1 113 
J 0
(203 2775);
DISPLAY 0.638298 (203 2775);
PAINT MONO (203 2775);
FORCEPROP 2 LAST PATH I197
J 0
(625 2850);
DISPLAY 1.021277 (625 2850);
PAINT ORANGE (625 2850);
DISPLAY INVISIBLE (625 2850);
FORCEPROP 1 LAST COMMENT_BODY TRUE
J 0
(700 2675);
DISPLAY 1.404255 (700 2675);
PAINT PEACH (700 2675);
DISPLAY INVISIBLE (700 2675);
FORCEPROP 1 LAST OFFPAGE TRUE
J 0
(900 2650);
DISPLAY 1.404255 (900 2650);
PAINT GREEN (900 2650);
DISPLAY INVISIBLE (900 2650);
FORCEPROP 2 LAST CDS_LIB mstr_standard
J 0
(575 2775);
PAINT ORANGE (575 2775);
DISPLAY INVISIBLE (575 2775);
FORCEADD RES..2
(1400 4225);
FORCEPROP 1 LAST PACK_TYPE 0402
J 0
(1440 4050);
DISPLAY 0.617021 (1440 4050);
PAINT SKYBLUE (1440 4050);
FORCEPROP 1 LASTPIN (1400 4325) $PN 1
J 0
(1405 4287);
DISPLAY 0.617021 (1405 4287);
PAINT ORANGE (1405 4287);
FORCEPROP 1 LASTPIN (1400 4125) $PN 2
J 0
(1405 4135);
DISPLAY 0.617021 (1405 4135);
PAINT ORANGE (1405 4135);
FORCEPROP 1 LAST TOLERANCE 1%
J 0
(1445 4250);
DISPLAY 0.617021 (1445 4250);
PAINT SKYBLUE (1445 4250);
FORCEPROP 1 LAST WATTAGE 1/16W
J 0
(1440 4200);
DISPLAY 0.617021 (1440 4200);
PAINT SKYBLUE (1440 4200);
FORCEPROP 1 LAST VALUE 1.00K
J 0
(1445 4300);
DISPLAY 0.617021 (1445 4300);
PAINT SKYBLUE (1445 4300);
FORCEPROP 1 LAST PART_NUMBER G21796-026
J 0
(1440 4100);
DISPLAY 0.617021 (1440 4100);
PAINT BLUE (1440 4100);
FORCEPROP 1 LAST LOCATION R1M23
J 0
(1445 4350);
DISPLAY 0.617021 (1445 4350);
PAINT AQUA (1445 4350);
FORCEPROP 1 LAST MATERIAL EMPTY
J 0
(1440 4150);
DISPLAY 0.617021 (1440 4150);
PAINT RED (1440 4150);
FORCEPROP 2 LAST CDS_LIB mstr_discrete
J 0
(1400 4225);
PAINT ORANGE (1400 4225);
DISPLAY INVISIBLE (1400 4225);
FORCEPROP 2 LAST ROOM DEBUG
J 0
(1450 4400);
DISPLAY 1.617021 (1450 4400);
PAINT WHITE (1450 4400);
DISPLAY INVISIBLE (1450 4400);
FORCEPROP 1 LAST PATH I199
J 0
(1450 4400);
DISPLAY 0.978723 (1450 4400);
PAINT WHITE (1450 4400);
DISPLAY INVISIBLE (1450 4400);
FORCEPROP 2 LAST SEC 1
J 0
(1450 4450);
DISPLAY 0.680851 (1450 4450);
PAINT MONO (1450 4450);
DISPLAY INVISIBLE (1450 4450);
FORCEPROP 2 LAST SEC_TYPE 0402
J 0
(1450 4450);
DISPLAY 1.021277 (1450 4450);
PAINT ORANGE (1450 4450);
DISPLAY INVISIBLE (1450 4450);
FORCEPROP 2 LAST BOM_COST DEBUG
J 0
(1450 4400);
DISPLAY 1.617021 (1450 4400);
PAINT WHITE (1450 4400);
DISPLAY INVISIBLE (1450 4400);
FORCEADD GND..1
(1400 3950);
FORCEPROP 3 LASTPIN (1400 4000) SIG_NAME GND\g
J 0
(1410 4010);
DISPLAY 0.659574 (1410 4010);
PAINT MONO (1410 4010);
DISPLAY INVISIBLE (1410 4010);
FORCEPROP 1 LAST PATH I200
J 0
(1475 3950);
DISPLAY 0.872340 (1475 3950);
PAINT AQUA (1475 3950);
DISPLAY INVISIBLE (1475 3950);
FORCEPROP 1 LAST BODY_TYPE PLUMBING
J 0
(1355 3907);
DISPLAY 0.340426 (1355 3907);
PAINT GREEN (1355 3907);
DISPLAY INVISIBLE (1355 3907);
FORCEPROP 2 LAST CDS_LIB mstr_symbols
J 0
(1400 3950);
PAINT ORANGE (1400 3950);
DISPLAY INVISIBLE (1400 3950);
FORCEPROP 1 LAST VOLTAGE 0.0V
J 0
(1355 3907);
DISPLAY 0.340426 (1355 3907);
PAINT SKYBLUE (1355 3907);
DISPLAY INVISIBLE (1355 3907);
FORCEPROP 1 LAST SIZE 1B
J 0
(1475 3900);
DISPLAY 2.382979 (1475 3900);
PAINT GREEN (1475 3900);
DISPLAY INVISIBLE (1475 3900);
FORCEPROP 1 LAST HDL_POWER GND
J 0
(1400 4100);
PAINT GREEN (1400 4100);
DISPLAY INVISIBLE (1400 4100);
FORCEADD VCC_CORE..1
(3575 1275);
FORCEPROP 3 LASTPIN (3575 1225) SIG_NAME P1V8_MCP_CPU0\g
J 0
(3585 1235);
DISPLAY 0.659574 (3585 1235);
PAINT MONO (3585 1235);
DISPLAY INVISIBLE (3585 1235);
FORCEPROP 1 LAST HDL_POWER P1V8_MCP_CPU0
J 1
(3575 1325);
DISPLAY 0.617021 (3575 1325);
PAINT GREEN (3575 1325);
FORCEPROP 2 LAST CDS_LIB mstr_symbols
J 0
(3575 1275);
PAINT ORANGE (3575 1275);
DISPLAY INVISIBLE (3575 1275);
FORCEPROP 1 LAST PATH I201
J 0
(3625 1300);
DISPLAY 0.872340 (3625 1300);
PAINT AQUA (3625 1300);
DISPLAY INVISIBLE (3625 1300);
FORCEADD RES..2
(3175 1025);
FORCEPROP 1 LAST LOCATION R1M19
J 0
(3220 1150);
DISPLAY 0.617021 (3220 1150);
PAINT AQUA (3220 1150);
FORCEPROP 1 LAST VALUE 1.00K
J 0
(3220 1100);
DISPLAY 0.617021 (3220 1100);
PAINT SKYBLUE (3220 1100);
FORCEPROP 1 LAST TOLERANCE 1%
J 0
(3220 1050);
DISPLAY 0.617021 (3220 1050);
PAINT SKYBLUE (3220 1050);
FORCEPROP 1 LAST WATTAGE 1/16W
J 0
(3215 1000);
DISPLAY 0.617021 (3215 1000);
PAINT SKYBLUE (3215 1000);
FORCEPROP 1 LASTPIN (3175 1125) $PN 1
J 0
(3180 1087);
DISPLAY 0.617021 (3180 1087);
PAINT ORANGE (3180 1087);
FORCEPROP 1 LAST PART_NUMBER G21796-026
J 0
(3215 900);
DISPLAY 0.617021 (3215 900);
PAINT BLUE (3215 900);
FORCEPROP 1 LAST MATERIAL CHIP
J 0
(3215 950);
DISPLAY 0.617021 (3215 950);
PAINT SKYBLUE (3215 950);
FORCEPROP 1 LASTPIN (3175 925) $PN 2
J 0
(3180 935);
DISPLAY 0.617021 (3180 935);
PAINT ORANGE (3180 935);
FORCEPROP 1 LAST PACK_TYPE 0402
J 0
(3215 850);
DISPLAY 0.617021 (3215 850);
PAINT SKYBLUE (3215 850);
FORCEPROP 2 LAST SEC 1
J 0
(3225 1250);
DISPLAY 0.680851 (3225 1250);
PAINT MONO (3225 1250);
DISPLAY INVISIBLE (3225 1250);
FORCEPROP 2 LAST BOM_COST DEBUG
J 0
(3225 1200);
DISPLAY 1.617021 (3225 1200);
PAINT WHITE (3225 1200);
DISPLAY INVISIBLE (3225 1200);
FORCEPROP 2 LAST SEC_TYPE 0402
J 0
(3225 1250);
DISPLAY 1.021277 (3225 1250);
PAINT ORANGE (3225 1250);
DISPLAY INVISIBLE (3225 1250);
FORCEPROP 2 LAST ROOM DEBUG
J 0
(3225 1200);
DISPLAY 1.617021 (3225 1200);
PAINT WHITE (3225 1200);
DISPLAY INVISIBLE (3225 1200);
FORCEPROP 1 LAST PATH I202
J 0
(3225 1200);
DISPLAY 0.978723 (3225 1200);
PAINT WHITE (3225 1200);
DISPLAY INVISIBLE (3225 1200);
FORCEPROP 2 LAST CDS_LIB mstr_discrete
J 0
(3175 1025);
PAINT ORANGE (3175 1025);
DISPLAY INVISIBLE (3175 1025);
FORCEADD RES..2
(3425 1025);
FORCEPROP 1 LAST VALUE 1.00K
J 0
(3470 1100);
DISPLAY 0.617021 (3470 1100);
PAINT SKYBLUE (3470 1100);
FORCEPROP 1 LAST TOLERANCE 1%
J 0
(3470 1050);
DISPLAY 0.617021 (3470 1050);
PAINT SKYBLUE (3470 1050);
FORCEPROP 1 LAST WATTAGE 1/16W
J 0
(3465 1000);
DISPLAY 0.617021 (3465 1000);
PAINT SKYBLUE (3465 1000);
FORCEPROP 1 LASTPIN (3425 1125) $PN 1
J 0
(3430 1087);
DISPLAY 0.617021 (3430 1087);
PAINT ORANGE (3430 1087);
FORCEPROP 1 LAST PART_NUMBER G21796-026
J 0
(3465 900);
DISPLAY 0.617021 (3465 900);
PAINT BLUE (3465 900);
FORCEPROP 1 LAST PACK_TYPE 0402
J 0
(3465 850);
DISPLAY 0.617021 (3465 850);
PAINT SKYBLUE (3465 850);
FORCEPROP 1 LAST MATERIAL CHIP
J 0
(3465 950);
DISPLAY 0.617021 (3465 950);
PAINT SKYBLUE (3465 950);
FORCEPROP 1 LASTPIN (3425 925) $PN 2
J 0
(3430 935);
DISPLAY 0.617021 (3430 935);
PAINT ORANGE (3430 935);
FORCEPROP 1 LAST LOCATION R9B12
J 0
(3470 1150);
DISPLAY 0.617021 (3470 1150);
PAINT AQUA (3470 1150);
FORCEPROP 2 LAST ROOM DEBUG
J 0
(3475 1200);
DISPLAY 1.617021 (3475 1200);
PAINT WHITE (3475 1200);
DISPLAY INVISIBLE (3475 1200);
FORCEPROP 2 LAST SEC 1
J 0
(3475 1250);
DISPLAY 0.680851 (3475 1250);
PAINT MONO (3475 1250);
DISPLAY INVISIBLE (3475 1250);
FORCEPROP 2 LAST SEC_TYPE 0402
J 0
(3475 1250);
DISPLAY 1.021277 (3475 1250);
PAINT ORANGE (3475 1250);
DISPLAY INVISIBLE (3475 1250);
FORCEPROP 2 LAST BOM_COST DEBUG
J 0
(3475 1200);
DISPLAY 1.617021 (3475 1200);
PAINT WHITE (3475 1200);
DISPLAY INVISIBLE (3475 1200);
FORCEPROP 1 LAST PATH I203
J 0
(3475 1200);
DISPLAY 0.978723 (3475 1200);
PAINT WHITE (3475 1200);
DISPLAY INVISIBLE (3475 1200);
FORCEPROP 2 LAST CDS_LIB mstr_discrete
J 0
(3425 1025);
PAINT ORANGE (3425 1025);
DISPLAY INVISIBLE (3425 1025);
FORCEADD RES..2
(2925 1025);
FORCEPROP 1 LAST LOCATION R1M20
J 0
(2970 1150);
DISPLAY 0.617021 (2970 1150);
PAINT AQUA (2970 1150);
FORCEPROP 1 LAST PART_NUMBER G21796-026
J 0
(2965 900);
DISPLAY 0.617021 (2965 900);
PAINT BLUE (2965 900);
FORCEPROP 1 LAST VALUE 1.00K
J 0
(2970 1100);
DISPLAY 0.617021 (2970 1100);
PAINT SKYBLUE (2970 1100);
FORCEPROP 1 LAST TOLERANCE 1%
J 0
(2970 1050);
DISPLAY 0.617021 (2970 1050);
PAINT SKYBLUE (2970 1050);
FORCEPROP 1 LAST PACK_TYPE 0402
J 0
(2965 850);
DISPLAY 0.617021 (2965 850);
PAINT SKYBLUE (2965 850);
FORCEPROP 1 LAST MATERIAL CHIP
J 0
(2965 950);
DISPLAY 0.617021 (2965 950);
PAINT SKYBLUE (2965 950);
FORCEPROP 1 LASTPIN (2925 1125) $PN 1
J 0
(2930 1087);
DISPLAY 0.617021 (2930 1087);
PAINT ORANGE (2930 1087);
FORCEPROP 1 LASTPIN (2925 925) $PN 2
J 0
(2930 935);
DISPLAY 0.617021 (2930 935);
PAINT ORANGE (2930 935);
FORCEPROP 1 LAST WATTAGE 1/16W
J 0
(2965 1000);
DISPLAY 0.617021 (2965 1000);
PAINT SKYBLUE (2965 1000);
FORCEPROP 2 LAST ROOM DEBUG
J 0
(2975 1200);
DISPLAY 1.617021 (2975 1200);
PAINT WHITE (2975 1200);
DISPLAY INVISIBLE (2975 1200);
FORCEPROP 2 LAST SEC 1
J 0
(2975 1250);
DISPLAY 0.680851 (2975 1250);
PAINT MONO (2975 1250);
DISPLAY INVISIBLE (2975 1250);
FORCEPROP 2 LAST SEC_TYPE 0402
J 0
(2975 1250);
DISPLAY 1.021277 (2975 1250);
PAINT ORANGE (2975 1250);
DISPLAY INVISIBLE (2975 1250);
FORCEPROP 2 LAST BOM_COST DEBUG
J 0
(2975 1200);
DISPLAY 1.617021 (2975 1200);
PAINT WHITE (2975 1200);
DISPLAY INVISIBLE (2975 1200);
FORCEPROP 1 LAST PATH I204
J 0
(2975 1200);
DISPLAY 0.978723 (2975 1200);
PAINT WHITE (2975 1200);
DISPLAY INVISIBLE (2975 1200);
FORCEPROP 2 LAST CDS_LIB mstr_discrete
J 0
(2925 1025);
PAINT ORANGE (2925 1025);
DISPLAY INVISIBLE (2925 1025);
FORCEADD RES..2
(3675 1025);
FORCEPROP 1 LAST PART_NUMBER G21796-026
J 0
(3715 900);
DISPLAY 0.617021 (3715 900);
PAINT BLUE (3715 900);
FORCEPROP 1 LAST VALUE 1.00K
J 0
(3720 1100);
DISPLAY 0.617021 (3720 1100);
PAINT SKYBLUE (3720 1100);
FORCEPROP 1 LAST TOLERANCE 1%
J 0
(3720 1050);
DISPLAY 0.617021 (3720 1050);
PAINT SKYBLUE (3720 1050);
FORCEPROP 1 LAST WATTAGE 1/16W
J 0
(3715 1000);
DISPLAY 0.617021 (3715 1000);
PAINT SKYBLUE (3715 1000);
FORCEPROP 1 LASTPIN (3675 1125) $PN 1
J 0
(3680 1087);
DISPLAY 0.617021 (3680 1087);
PAINT ORANGE (3680 1087);
FORCEPROP 1 LAST MATERIAL CHIP
J 0
(3715 950);
DISPLAY 0.617021 (3715 950);
PAINT SKYBLUE (3715 950);
FORCEPROP 1 LASTPIN (3675 925) $PN 2
J 0
(3680 935);
DISPLAY 0.617021 (3680 935);
PAINT ORANGE (3680 935);
FORCEPROP 1 LAST PACK_TYPE 0402
J 0
(3715 850);
DISPLAY 0.617021 (3715 850);
PAINT SKYBLUE (3715 850);
FORCEPROP 1 LAST LOCATION R1M21
J 0
(3720 1150);
DISPLAY 0.617021 (3720 1150);
PAINT AQUA (3720 1150);
FORCEPROP 2 LAST BOM_COST DEBUG
J 0
(3725 1200);
DISPLAY 1.617021 (3725 1200);
PAINT WHITE (3725 1200);
DISPLAY INVISIBLE (3725 1200);
FORCEPROP 2 LAST SEC_TYPE 0402
J 0
(3725 1250);
DISPLAY 1.021277 (3725 1250);
PAINT ORANGE (3725 1250);
DISPLAY INVISIBLE (3725 1250);
FORCEPROP 2 LAST SEC 1
J 0
(3725 1250);
DISPLAY 0.680851 (3725 1250);
PAINT MONO (3725 1250);
DISPLAY INVISIBLE (3725 1250);
FORCEPROP 2 LAST ROOM DEBUG
J 0
(3725 1200);
DISPLAY 1.617021 (3725 1200);
PAINT WHITE (3725 1200);
DISPLAY INVISIBLE (3725 1200);
FORCEPROP 1 LAST PATH I205
J 0
(3725 1200);
DISPLAY 0.978723 (3725 1200);
PAINT WHITE (3725 1200);
DISPLAY INVISIBLE (3725 1200);
FORCEPROP 2 LAST CDS_LIB mstr_discrete
J 0
(3675 1025);
PAINT ORANGE (3675 1025);
DISPLAY INVISIBLE (3675 1025);
FORCEADD 74CBTLV1G125..1
(1625 3375);
FORCEPROP 2 LASTPIN (1375 3375) $PN 2
J 2
(1365 3385);
DISPLAY 0.617021 (1365 3385);
PAINT ORANGE (1365 3385);
FORCEPROP 2 LASTPIN (1375 3325) $PN 1
J 2
(1365 3335);
DISPLAY 0.617021 (1365 3335);
PAINT ORANGE (1365 3335);
FORCEPROP 1 LAST MATERIAL IC
J 0
(1450 3595);
DISPLAY 0.617021 (1450 3595);
PAINT SKYBLUE (1450 3595);
FORCEPROP 1 LAST PACK_TYPE SMLF
J 0
(1450 3545);
DISPLAY 0.617021 (1450 3545);
PAINT SKYBLUE (1450 3545);
FORCEPROP 1 LAST PART_NUMBER C88177-001
J 0
(1460 3235);
DISPLAY 0.617021 (1460 3235);
PAINT BLUE (1460 3235);
FORCEPROP 1 LAST LOCATION U4R1
J 0
(1459 3506);
DISPLAY 0.617021 (1459 3506);
PAINT AQUA (1459 3506);
FORCEPROP 1 LAST POWER_GROUP VCC=P3V3_STBY;GND=GND;
J 0
(1400 3175);
DISPLAY 0.617021 (1400 3175);
PAINT ORANGE (1400 3175);
FORCEPROP 2 LASTPIN (1875 3375) $PN 4
J 0
(1885 3385);
DISPLAY 0.617021 (1885 3385);
PAINT ORANGE (1885 3385);
FORCEPROP 2 LAST SEC_TYPE SMLF
J 0
(1450 3625);
DISPLAY 1.021277 (1450 3625);
PAINT ORANGE (1450 3625);
DISPLAY INVISIBLE (1450 3625);
FORCEPROP 2 LAST BOM_COST DEBUG
J 0
(1450 3700);
DISPLAY 1.021277 (1450 3700);
PAINT ORANGE (1450 3700);
DISPLAY INVISIBLE (1450 3700);
FORCEPROP 2 LAST SEC 1
J 0
(1450 3625);
DISPLAY 0.680851 (1450 3625);
PAINT MONO (1450 3625);
DISPLAY INVISIBLE (1450 3625);
FORCEPROP 2 LAST ROOM DEBUG
J 0
(1450 3700);
DISPLAY 1.021277 (1450 3700);
PAINT ORANGE (1450 3700);
DISPLAY INVISIBLE (1450 3700);
FORCEPROP 1 LAST PATH I206
J 0
(1725 3495);
DISPLAY 0.872340 (1725 3495);
PAINT PINK (1725 3495);
DISPLAY INVISIBLE (1725 3495);
FORCEPROP 2 LAST CDS_LIB mstr_ttl
J 0
(1625 3375);
PAINT ORANGE (1625 3375);
DISPLAY INVISIBLE (1625 3375);
FORCEADD OFFPAGE..1
(2425 800);
FORCEPROP 2 LAST $XR0 113 
J 0
(2173 800);
DISPLAY 0.638298 (2173 800);
PAINT MONO (2173 800);
FORCEPROP 2 LAST $XR1 29 
J 0
(2083 800);
DISPLAY 0.638298 (2083 800);
PAINT MONO (2083 800);
FORCEPROP 2 LAST $XR2 63 
J 0
(1993 800);
DISPLAY 0.638298 (1993 800);
PAINT MONO (1993 800);
FORCEPROP 1 LAST OFFPAGE TRUE
J 0
(2750 675);
DISPLAY 1.404255 (2750 675);
PAINT GREEN (2750 675);
DISPLAY INVISIBLE (2750 675);
FORCEPROP 1 LAST COMMENT_BODY TRUE
J 0
(2550 700);
DISPLAY 1.404255 (2550 700);
PAINT PEACH (2550 700);
DISPLAY INVISIBLE (2550 700);
FORCEPROP 2 LAST CDS_LIB mstr_standard
J 0
(2425 800);
PAINT MONO (2425 800);
DISPLAY INVISIBLE (2425 800);
FORCEPROP 2 LAST PATH I212
J 0
(2150 850);
DISPLAY 1.021277 (2150 850);
PAINT ORANGE (2150 850);
DISPLAY INVISIBLE (2150 850);
FORCEADD OFFPAGE..1
(2425 700);
FORCEPROP 2 LAST $XR0 113 
J 0
(2173 700);
DISPLAY 0.638298 (2173 700);
PAINT MONO (2173 700);
FORCEPROP 2 LAST $XR1 29 
J 0
(2083 700);
DISPLAY 0.638298 (2083 700);
PAINT MONO (2083 700);
FORCEPROP 2 LAST $XR2 63 
J 0
(1993 700);
DISPLAY 0.638298 (1993 700);
PAINT MONO (1993 700);
FORCEPROP 1 LAST OFFPAGE TRUE
J 0
(2750 575);
DISPLAY 1.404255 (2750 575);
PAINT GREEN (2750 575);
DISPLAY INVISIBLE (2750 575);
FORCEPROP 1 LAST COMMENT_BODY TRUE
J 0
(2550 600);
DISPLAY 1.404255 (2550 600);
PAINT PEACH (2550 600);
DISPLAY INVISIBLE (2550 600);
FORCEPROP 2 LAST CDS_LIB mstr_standard
J 0
(2425 700);
PAINT MONO (2425 700);
DISPLAY INVISIBLE (2425 700);
FORCEPROP 2 LAST PATH I213
J 0
(2150 750);
DISPLAY 1.021277 (2150 750);
PAINT ORANGE (2150 750);
DISPLAY INVISIBLE (2150 750);
FORCEADD OFFPAGE..1
(2425 750);
FORCEPROP 2 LAST $XR0 113 
J 0
(2173 750);
DISPLAY 0.638298 (2173 750);
PAINT MONO (2173 750);
FORCEPROP 1 LAST OFFPAGE TRUE
J 0
(2750 625);
DISPLAY 1.404255 (2750 625);
PAINT GREEN (2750 625);
DISPLAY INVISIBLE (2750 625);
FORCEPROP 1 LAST COMMENT_BODY TRUE
J 0
(2550 650);
DISPLAY 1.404255 (2550 650);
PAINT PEACH (2550 650);
DISPLAY INVISIBLE (2550 650);
FORCEPROP 2 LAST CDS_LIB mstr_standard
J 0
(2425 750);
DISPLAY 2.212766 (2425 750);
PAINT ORANGE (2425 750);
DISPLAY INVISIBLE (2425 750);
FORCEPROP 2 LAST PATH I214
J 0
(2150 800);
DISPLAY 1.021277 (2150 800);
PAINT ORANGE (2150 800);
DISPLAY INVISIBLE (2150 800);
FORCEADD OFFPAGE..1
(2425 850);
FORCEPROP 2 LAST $XR0 113 
J 0
(2173 850);
DISPLAY 0.638298 (2173 850);
PAINT MONO (2173 850);
FORCEPROP 1 LAST OFFPAGE TRUE
J 0
(2750 725);
DISPLAY 1.404255 (2750 725);
PAINT GREEN (2750 725);
DISPLAY INVISIBLE (2750 725);
FORCEPROP 1 LAST COMMENT_BODY TRUE
J 0
(2550 750);
DISPLAY 1.404255 (2550 750);
PAINT PEACH (2550 750);
DISPLAY INVISIBLE (2550 750);
FORCEPROP 2 LAST CDS_LIB mstr_standard
J 0
(2425 850);
DISPLAY 2.212766 (2425 850);
PAINT ORANGE (2425 850);
DISPLAY INVISIBLE (2425 850);
FORCEPROP 2 LAST PATH I215
J 0
(2150 900);
DISPLAY 1.021277 (2150 900);
PAINT ORANGE (2150 900);
DISPLAY INVISIBLE (2150 900);
FORCEADD VCC_CORE..1
(1275 2500);
FORCEPROP 3 LASTPIN (1275 2450) SIG_NAME P1V8_MCP_CPU1\g
J 0
(1285 2460);
DISPLAY 0.659574 (1285 2460);
PAINT MONO (1285 2460);
DISPLAY INVISIBLE (1285 2460);
FORCEPROP 1 LAST HDL_POWER P1V8_MCP_CPU1
J 1
(1275 2550);
DISPLAY 0.617021 (1275 2550);
PAINT GREEN (1275 2550);
FORCEPROP 2 LAST CDS_LIB mstr_symbols
J 0
(1275 2500);
PAINT ORANGE (1275 2500);
DISPLAY INVISIBLE (1275 2500);
FORCEPROP 1 LAST PATH I236
J 0
(1325 2525);
DISPLAY 0.872340 (1325 2525);
PAINT AQUA (1325 2525);
DISPLAY INVISIBLE (1325 2525);
FORCEPROP 0 LAST VOLTAGE 1.8
J 0
(1275 2650);
DISPLAY 1.021277 (1275 2650);
PAINT SKYBLUE (1275 2650);
DISPLAY INVISIBLE (1275 2650);
FORCEADD OFFPAGE..1
(575 3325);
FORCEPROP 2 LAST $XR0 21 
J 0
(354 3325);
DISPLAY 0.638298 (354 3325);
PAINT MONO (354 3325);
FORCEPROP 2 LAST $XR1 190 
J 0
(234 3325);
DISPLAY 0.638298 (234 3325);
PAINT MONO (234 3325);
FORCEPROP 2 LAST PATH I238
J 0
(625 3400);
DISPLAY 1.021277 (625 3400);
PAINT ORANGE (625 3400);
DISPLAY INVISIBLE (625 3400);
FORCEPROP 1 LAST COMMENT_BODY TRUE
J 0
(700 3225);
DISPLAY 1.404255 (700 3225);
PAINT PEACH (700 3225);
DISPLAY INVISIBLE (700 3225);
FORCEPROP 1 LAST OFFPAGE TRUE
J 0
(900 3200);
DISPLAY 1.404255 (900 3200);
PAINT GREEN (900 3200);
DISPLAY INVISIBLE (900 3200);
FORCEPROP 2 LAST CDS_LIB mstr_standard
J 0
(575 3325);
PAINT ORANGE (575 3325);
DISPLAY INVISIBLE (575 3325);
FORCEADD RES..1
(-2600 4625);
FORCEPROP 1 LAST VALUE 0.0
J 2
(-2725 4575);
DISPLAY 0.617021 (-2725 4575);
PAINT SKYBLUE (-2725 4575);
FORCEPROP 1 LAST TOLERANCE 5%
J 0
(-2700 4575);
DISPLAY 0.617021 (-2700 4575);
PAINT SKYBLUE (-2700 4575);
FORCEPROP 1 LAST PACK_TYPE 0402
J 0
(-2725 4525);
DISPLAY 0.617021 (-2725 4525);
PAINT SKYBLUE (-2725 4525);
FORCEPROP 1 LASTPIN (-2700 4625) $PN 1
J 0
(-2688 4637);
DISPLAY 0.617021 (-2688 4637);
PAINT ORANGE (-2688 4637);
FORCEPROP 1 LAST WATTAGE 1/16W
J 2
(-2525 4575);
DISPLAY 0.617021 (-2525 4575);
PAINT SKYBLUE (-2525 4575);
FORCEPROP 1 LAST PART_NUMBER G21497-005
J 0
(-2625 4525);
DISPLAY 0.617021 (-2625 4525);
PAINT BLUE (-2625 4525);
FORCEPROP 1 LAST LOCATION R9B11
J 0
(-2650 4675);
DISPLAY 0.617021 (-2650 4675);
PAINT AQUA (-2650 4675);
FORCEPROP 1 LAST MATERIAL CHIP
J 0
(-2500 4575);
DISPLAY 0.617021 (-2500 4575);
PAINT SKYBLUE (-2500 4575);
FORCEPROP 1 LASTPIN (-2500 4625) $PN 2
J 0
(-2538 4637);
DISPLAY 0.617021 (-2538 4637);
PAINT ORANGE (-2538 4637);
FORCEPROP 2 LAST SEC 1
J 0
(-2650 4825);
DISPLAY 0.680851 (-2650 4825);
PAINT MONO (-2650 4825);
DISPLAY INVISIBLE (-2650 4825);
FORCEPROP 2 LAST CDS_LIB mstr_discrete
J 0
(-2600 4625);
PAINT ORANGE (-2600 4625);
DISPLAY INVISIBLE (-2600 4625);
FORCEPROP 1 LAST PATH I239
J 0
(-2650 4775);
DISPLAY 0.978723 (-2650 4775);
PAINT WHITE (-2650 4775);
DISPLAY INVISIBLE (-2650 4775);
FORCEPROP 2 LAST SEC_TYPE 0402
J 0
(-2650 4825);
DISPLAY 1.021277 (-2650 4825);
PAINT ORANGE (-2650 4825);
DISPLAY INVISIBLE (-2650 4825);
FORCEADD RES..1
(-2600 4375);
FORCEPROP 1 LAST VALUE 0.0
J 2
(-2725 4325);
DISPLAY 0.617021 (-2725 4325);
PAINT SKYBLUE (-2725 4325);
FORCEPROP 1 LAST TOLERANCE 5%
J 0
(-2700 4325);
DISPLAY 0.617021 (-2700 4325);
PAINT SKYBLUE (-2700 4325);
FORCEPROP 1 LAST PACK_TYPE 0402
J 0
(-2725 4275);
DISPLAY 0.617021 (-2725 4275);
PAINT SKYBLUE (-2725 4275);
FORCEPROP 1 LASTPIN (-2700 4375) $PN 1
J 0
(-2688 4387);
DISPLAY 0.617021 (-2688 4387);
PAINT ORANGE (-2688 4387);
FORCEPROP 1 LAST WATTAGE 1/16W
J 2
(-2525 4325);
DISPLAY 0.617021 (-2525 4325);
PAINT SKYBLUE (-2525 4325);
FORCEPROP 1 LAST LOCATION R9B13
J 0
(-2650 4425);
DISPLAY 0.617021 (-2650 4425);
PAINT AQUA (-2650 4425);
FORCEPROP 1 LAST PART_NUMBER G21497-005
J 0
(-2625 4275);
DISPLAY 0.617021 (-2625 4275);
PAINT BLUE (-2625 4275);
FORCEPROP 1 LASTPIN (-2500 4375) $PN 2
J 0
(-2538 4387);
DISPLAY 0.617021 (-2538 4387);
PAINT ORANGE (-2538 4387);
FORCEPROP 1 LAST MATERIAL CHIP
J 0
(-2500 4325);
DISPLAY 0.617021 (-2500 4325);
PAINT SKYBLUE (-2500 4325);
FORCEPROP 2 LAST CDS_LIB mstr_discrete
J 0
(-2600 4375);
PAINT ORANGE (-2600 4375);
DISPLAY INVISIBLE (-2600 4375);
FORCEPROP 2 LAST SEC 1
J 0
(-2650 4575);
DISPLAY 0.680851 (-2650 4575);
PAINT MONO (-2650 4575);
DISPLAY INVISIBLE (-2650 4575);
FORCEPROP 1 LAST PATH I240
J 0
(-2650 4525);
DISPLAY 0.978723 (-2650 4525);
PAINT WHITE (-2650 4525);
DISPLAY INVISIBLE (-2650 4525);
FORCEPROP 2 LAST SEC_TYPE 0402
J 0
(-2650 4575);
DISPLAY 1.021277 (-2650 4575);
PAINT ORANGE (-2650 4575);
DISPLAY INVISIBLE (-2650 4575);
FORCEADD VCC_CORE..1
(1275 3675);
FORCEPROP 3 LASTPIN (1275 3625) SIG_NAME P1V8_MCP_CPU0\g
J 0
(1285 3635);
DISPLAY 0.659574 (1285 3635);
PAINT MONO (1285 3635);
DISPLAY INVISIBLE (1285 3635);
FORCEPROP 1 LAST HDL_POWER P1V8_MCP_CPU0
J 1
(1275 3725);
DISPLAY 0.617021 (1275 3725);
PAINT GREEN (1275 3725);
FORCEPROP 2 LAST CDS_LIB mstr_symbols
J 0
(1275 3675);
PAINT ORANGE (1275 3675);
DISPLAY INVISIBLE (1275 3675);
FORCEPROP 1 LAST PATH I241
J 0
(1325 3700);
DISPLAY 0.872340 (1325 3700);
PAINT AQUA (1325 3700);
DISPLAY INVISIBLE (1325 3700);
FORCEADD OFFPAGE..2
(2925 3025);
FORCEPROP 2 LAST $XR0 29 
J 0
(3114 3025);
DISPLAY 0.638298 (3114 3025);
PAINT MONO (3114 3025);
FORCEPROP 2 LAST $XR1 113 
J 0
(3204 3025);
DISPLAY 0.638298 (3204 3025);
PAINT MONO (3204 3025);
FORCEPROP 1 LAST COMMENT_BODY TRUE
J 0
(2880 2930);
DISPLAY 0.872340 (2880 2930);
PAINT GREEN (2880 2930);
DISPLAY INVISIBLE (2880 2930);
FORCEPROP 2 LAST CDS_LIB mstr_standard
J 0
(2925 3025);
PAINT ORANGE (2925 3025);
DISPLAY INVISIBLE (2925 3025);
FORCEPROP 1 LAST OFFPAGE TRUE
J 0
(3250 2900);
DISPLAY 0.872340 (3250 2900);
PAINT GREEN (3250 2900);
DISPLAY INVISIBLE (3250 2900);
FORCEPROP 2 LAST PATH I242
J 0
(3100 3100);
DISPLAY 1.021277 (3100 3100);
PAINT ORANGE (3100 3100);
DISPLAY INVISIBLE (3100 3100);
FORCEADD OFFPAGE..2
(2925 2475);
FORCEPROP 2 LAST $XR0 113 
J 0
(3114 2475);
DISPLAY 0.638298 (3114 2475);
PAINT MONO (3114 2475);
FORCEPROP 2 LAST $XR1 29 
J 0
(3234 2475);
DISPLAY 0.638298 (3234 2475);
PAINT MONO (3234 2475);
FORCEPROP 2 LAST $XR2 63 
J 0
(3324 2475);
DISPLAY 0.638298 (3324 2475);
PAINT MONO (3324 2475);
FORCEPROP 1 LAST COMMENT_BODY TRUE
J 0
(2880 2380);
DISPLAY 0.872340 (2880 2380);
PAINT GREEN (2880 2380);
DISPLAY INVISIBLE (2880 2380);
FORCEPROP 2 LAST CDS_LIB mstr_standard
J 0
(2925 2475);
PAINT ORANGE (2925 2475);
DISPLAY INVISIBLE (2925 2475);
FORCEPROP 2 LAST PATH I243
J 0
(3100 2550);
DISPLAY 1.021277 (3100 2550);
PAINT ORANGE (3100 2550);
DISPLAY INVISIBLE (3100 2550);
FORCEPROP 1 LAST OFFPAGE TRUE
J 0
(3250 2350);
DISPLAY 0.872340 (3250 2350);
PAINT GREEN (3250 2350);
DISPLAY INVISIBLE (3250 2350);
FORCEADD OFFPAGE..2
(2950 1900);
FORCEPROP 2 LAST $XR0 113 
J 0
(3139 1900);
DISPLAY 0.638298 (3139 1900);
PAINT MONO (3139 1900);
FORCEPROP 2 LAST $XR1 63 
J 0
(3259 1900);
DISPLAY 0.638298 (3259 1900);
PAINT MONO (3259 1900);
FORCEPROP 1 LAST COMMENT_BODY TRUE
J 0
(2905 1805);
DISPLAY 0.872340 (2905 1805);
PAINT GREEN (2905 1805);
DISPLAY INVISIBLE (2905 1805);
FORCEPROP 2 LAST CDS_LIB mstr_standard
J 0
(2950 1900);
PAINT ORANGE (2950 1900);
DISPLAY INVISIBLE (2950 1900);
FORCEPROP 2 LAST PATH I244
J 0
(3125 1975);
DISPLAY 1.021277 (3125 1975);
PAINT ORANGE (3125 1975);
DISPLAY INVISIBLE (3125 1975);
FORCEPROP 1 LAST OFFPAGE TRUE
J 0
(3275 1775);
DISPLAY 0.872340 (3275 1775);
PAINT GREEN (3275 1775);
DISPLAY INVISIBLE (3275 1775);
FORCEADD VCC_CORE..1
(1275 3075);
FORCEPROP 3 LASTPIN (1275 3025) SIG_NAME P1V8_MCP_CPU0\g
J 0
(1285 3035);
DISPLAY 0.659574 (1285 3035);
PAINT MONO (1285 3035);
DISPLAY INVISIBLE (1285 3035);
FORCEPROP 1 LAST HDL_POWER P1V8_MCP_CPU0
J 1
(1275 3125);
DISPLAY 0.617021 (1275 3125);
PAINT GREEN (1275 3125);
FORCEPROP 2 LAST CDS_LIB mstr_symbols
J 0
(1275 3075);
PAINT ORANGE (1275 3075);
DISPLAY INVISIBLE (1275 3075);
FORCEPROP 1 LAST PATH I245
J 0
(1325 3100);
DISPLAY 0.872340 (1325 3100);
PAINT AQUA (1325 3100);
DISPLAY INVISIBLE (1325 3100);
FORCEADD CAP_A..1
R 2
(2125 3200);
FORCEPROP 1 LAST MATERIAL X7R
J 2
(2075 3100);
DISPLAY 0.617021 (2075 3100);
PAINT SKYBLUE (2075 3100);
FORCEPROP 1 LAST VOLTAGE 16V
J 2
(2075 3200);
DISPLAY 0.617021 (2075 3200);
PAINT SKYBLUE (2075 3200);
FORCEPROP 1 LAST PACK_TYPE 0402V
J 2
(2075 3000);
DISPLAY 0.617021 (2075 3000);
PAINT SKYBLUE (2075 3000);
FORCEPROP 1 LAST TOLERANCE 10%
J 2
(2075 3150);
DISPLAY 0.617021 (2075 3150);
PAINT SKYBLUE (2075 3150);
FORCEPROP 1 LAST VALUE 0.1UF
J 2
(2075 3250);
DISPLAY 0.617021 (2075 3250);
PAINT SKYBLUE (2075 3250);
FORCEPROP 1 LAST PART_NUMBER A36096-030
J 2
(2075 3050);
DISPLAY 0.617021 (2075 3050);
PAINT BLUE (2075 3050);
FORCEPROP 1 LAST LOCATION C4R2
J 2
(2075 3300);
DISPLAY 0.617021 (2075 3300);
PAINT AQUA (2075 3300);
FORCEPROP 1 LASTPIN (2125 3300) $PN 1
J 2
(2115 3280);
DISPLAY 0.617021 (2115 3280);
PAINT ORANGE (2115 3280);
FORCEPROP 1 LASTPIN (2125 3100) $PN 2
J 2
(2115 3080);
DISPLAY 0.617021 (2115 3080);
PAINT ORANGE (2115 3080);
FORCEPROP 2 LAST CDS_LIB dev_discrete
J 0
(2125 3200);
PAINT ORANGE (2125 3200);
DISPLAY INVISIBLE (2125 3200);
FORCEPROP 1 LAST PATH I246
J 2
(2075 3350);
DISPLAY 0.978723 (2075 3350);
PAINT WHITE (2075 3350);
DISPLAY INVISIBLE (2075 3350);
FORCEPROP 2 LAST ROOM DEBUG
J 2
(2075 3400);
DISPLAY 1.021277 (2075 3400);
PAINT ORANGE (2075 3400);
DISPLAY INVISIBLE (2075 3400);
FORCEPROP 2 LAST CDS_SEC 1
J 0
(2075 3350);
PAINT ORANGE (2075 3350);
DISPLAY INVISIBLE (2075 3350);
FORCEPROP 2 LAST SEC_TYPE 0402V
J 2
(2075 3400);
DISPLAY 1.021277 (2075 3400);
PAINT ORANGE (2075 3400);
DISPLAY INVISIBLE (2075 3400);
FORCEPROP 2 LAST SEC 1
J 2
(2075 3400);
DISPLAY 0.680851 (2075 3400);
PAINT MONO (2075 3400);
DISPLAY INVISIBLE (2075 3400);
FORCEADD GND..1
(2125 3000);
FORCEPROP 3 LASTPIN (2125 3050) SIG_NAME GND\g
J 0
(2135 3060);
DISPLAY 0.659574 (2135 3060);
PAINT MONO (2135 3060);
DISPLAY INVISIBLE (2135 3060);
FORCEPROP 1 LAST BODY_TYPE PLUMBING
J 0
(2080 2957);
DISPLAY 0.340426 (2080 2957);
PAINT GREEN (2080 2957);
DISPLAY INVISIBLE (2080 2957);
FORCEPROP 2 LAST CDS_LIB mstr_symbols
J 0
(2125 3000);
PAINT ORANGE (2125 3000);
DISPLAY INVISIBLE (2125 3000);
FORCEPROP 1 LAST VOLTAGE 0.0V
J 0
(2080 2957);
DISPLAY 0.340426 (2080 2957);
PAINT SKYBLUE (2080 2957);
DISPLAY INVISIBLE (2080 2957);
FORCEPROP 1 LAST SIZE 1B
J 0
(2200 2950);
DISPLAY 2.382979 (2200 2950);
PAINT GREEN (2200 2950);
DISPLAY INVISIBLE (2200 2950);
FORCEPROP 1 LAST PATH I247
J 0
(2200 3000);
DISPLAY 0.872340 (2200 3000);
PAINT AQUA (2200 3000);
DISPLAY INVISIBLE (2200 3000);
FORCEPROP 1 LAST HDL_POWER GND
J 0
(2125 3150);
PAINT GREEN (2125 3150);
DISPLAY INVISIBLE (2125 3150);
FORCEADD CAP_A..1
R 2
(2125 2650);
FORCEPROP 1 LAST MATERIAL X7R
J 2
(2075 2550);
DISPLAY 0.617021 (2075 2550);
PAINT SKYBLUE (2075 2550);
FORCEPROP 1 LAST VOLTAGE 16V
J 2
(2075 2650);
DISPLAY 0.617021 (2075 2650);
PAINT SKYBLUE (2075 2650);
FORCEPROP 1 LAST PACK_TYPE 0402V
J 2
(2075 2450);
DISPLAY 0.617021 (2075 2450);
PAINT SKYBLUE (2075 2450);
FORCEPROP 1 LAST TOLERANCE 10%
J 2
(2075 2600);
DISPLAY 0.617021 (2075 2600);
PAINT SKYBLUE (2075 2600);
FORCEPROP 1 LAST VALUE 0.1UF
J 2
(2075 2700);
DISPLAY 0.617021 (2075 2700);
PAINT SKYBLUE (2075 2700);
FORCEPROP 1 LAST PART_NUMBER A36096-030
J 2
(2075 2500);
DISPLAY 0.617021 (2075 2500);
PAINT BLUE (2075 2500);
FORCEPROP 1 LAST LOCATION C1M33
J 2
(2075 2750);
DISPLAY 0.617021 (2075 2750);
PAINT AQUA (2075 2750);
FORCEPROP 1 LASTPIN (2125 2550) $PN 2
J 2
(2115 2530);
DISPLAY 0.617021 (2115 2530);
PAINT ORANGE (2115 2530);
FORCEPROP 1 LASTPIN (2125 2750) $PN 1
J 2
(2115 2730);
DISPLAY 0.617021 (2115 2730);
PAINT ORANGE (2115 2730);
FORCEPROP 2 LAST CDS_LIB dev_discrete
J 0
(2125 2650);
PAINT ORANGE (2125 2650);
DISPLAY INVISIBLE (2125 2650);
FORCEPROP 2 LAST CDS_SEC 1
J 0
(2075 2800);
PAINT ORANGE (2075 2800);
DISPLAY INVISIBLE (2075 2800);
FORCEPROP 1 LAST PATH I248
J 2
(2075 2800);
DISPLAY 0.978723 (2075 2800);
PAINT WHITE (2075 2800);
DISPLAY INVISIBLE (2075 2800);
FORCEPROP 2 LAST ROOM DEBUG
J 2
(2075 2800);
DISPLAY 1.617021 (2075 2800);
PAINT WHITE (2075 2800);
DISPLAY INVISIBLE (2075 2800);
FORCEPROP 2 LAST BOM_COST DEBUG
J 0
(2075 2800);
DISPLAY 1.617021 (2075 2800);
PAINT WHITE (2075 2800);
DISPLAY INVISIBLE (2075 2800);
FORCEPROP 2 LAST SEC_TYPE 0402V
J 0
(2075 2850);
DISPLAY 1.021277 (2075 2850);
PAINT ORANGE (2075 2850);
DISPLAY INVISIBLE (2075 2850);
FORCEPROP 2 LAST SEC 1
J 0
(2075 2850);
DISPLAY 0.680851 (2075 2850);
PAINT MONO (2075 2850);
DISPLAY INVISIBLE (2075 2850);
FORCEADD GND..1
(2125 2450);
FORCEPROP 3 LASTPIN (2125 2500) SIG_NAME GND\g
J 0
(2135 2510);
DISPLAY 0.659574 (2135 2510);
PAINT MONO (2135 2510);
DISPLAY INVISIBLE (2135 2510);
FORCEPROP 2 LAST ROOM DEBUG
J 0
(1650 2525);
DISPLAY 1.617021 (1650 2525);
PAINT WHITE (1650 2525);
DISPLAY INVISIBLE (1650 2525);
FORCEPROP 2 LAST BOM_COST DEBUG
J 0
(1650 2575);
DISPLAY 1.617021 (1650 2575);
PAINT WHITE (1650 2575);
DISPLAY INVISIBLE (1650 2575);
FORCEPROP 1 LAST VOLTAGE 0.0V
J 0
(2080 2407);
DISPLAY 0.340426 (2080 2407);
PAINT SKYBLUE (2080 2407);
DISPLAY INVISIBLE (2080 2407);
FORCEPROP 2 LAST CDS_LIB mstr_symbols
J 0
(2125 2450);
PAINT ORANGE (2125 2450);
DISPLAY INVISIBLE (2125 2450);
FORCEPROP 1 LAST BODY_TYPE PLUMBING
J 0
(2080 2407);
DISPLAY 0.340426 (2080 2407);
PAINT GREEN (2080 2407);
DISPLAY INVISIBLE (2080 2407);
FORCEPROP 1 LAST SIZE 1B
J 0
(2200 2400);
DISPLAY 1.893617 (2200 2400);
PAINT GREEN (2200 2400);
DISPLAY INVISIBLE (2200 2400);
FORCEPROP 1 LAST PATH I249
J 0
(2200 2450);
DISPLAY 0.872340 (2200 2450);
PAINT AQUA (2200 2450);
DISPLAY INVISIBLE (2200 2450);
FORCEPROP 1 LAST HDL_POWER GND
J 0
(2125 2600);
PAINT GREEN (2125 2600);
DISPLAY INVISIBLE (2125 2600);
FORCEADD CAP_A..1
R 2
(2150 2075);
FORCEPROP 1 LAST MATERIAL X7R
J 2
(2100 1975);
DISPLAY 0.617021 (2100 1975);
PAINT SKYBLUE (2100 1975);
FORCEPROP 1 LAST VOLTAGE 16V
J 2
(2100 2075);
DISPLAY 0.617021 (2100 2075);
PAINT SKYBLUE (2100 2075);
FORCEPROP 1 LAST PACK_TYPE 0402V
J 2
(2100 1875);
DISPLAY 0.617021 (2100 1875);
PAINT SKYBLUE (2100 1875);
FORCEPROP 1 LAST TOLERANCE 10%
J 2
(2100 2025);
DISPLAY 0.617021 (2100 2025);
PAINT SKYBLUE (2100 2025);
FORCEPROP 1 LAST VALUE 0.1UF
J 2
(2100 2125);
DISPLAY 0.617021 (2100 2125);
PAINT SKYBLUE (2100 2125);
FORCEPROP 1 LAST PART_NUMBER A36096-030
J 2
(2100 1925);
DISPLAY 0.617021 (2100 1925);
PAINT BLUE (2100 1925);
FORCEPROP 1 LAST LOCATION C6M6
J 2
(2100 2175);
DISPLAY 0.617021 (2100 2175);
PAINT AQUA (2100 2175);
FORCEPROP 1 LASTPIN (2150 1975) $PN 2
J 2
(2140 1955);
DISPLAY 0.617021 (2140 1955);
PAINT ORANGE (2140 1955);
FORCEPROP 1 LASTPIN (2150 2175) $PN 1
J 2
(2140 2155);
DISPLAY 0.617021 (2140 2155);
PAINT ORANGE (2140 2155);
FORCEPROP 2 LAST CDS_LIB dev_discrete
J 0
(2150 2075);
PAINT ORANGE (2150 2075);
DISPLAY INVISIBLE (2150 2075);
FORCEPROP 2 LAST SEC 1
J 0
(2100 2275);
DISPLAY 0.680851 (2100 2275);
PAINT MONO (2100 2275);
DISPLAY INVISIBLE (2100 2275);
FORCEPROP 2 LAST CDS_SEC 1
J 0
(2100 2225);
PAINT ORANGE (2100 2225);
DISPLAY INVISIBLE (2100 2225);
FORCEPROP 2 LAST BOM_COST DEBUG
J 0
(2100 2225);
DISPLAY 1.617021 (2100 2225);
PAINT WHITE (2100 2225);
DISPLAY INVISIBLE (2100 2225);
FORCEPROP 2 LAST ROOM DEBUG
J 2
(2100 2225);
DISPLAY 1.617021 (2100 2225);
PAINT WHITE (2100 2225);
DISPLAY INVISIBLE (2100 2225);
FORCEPROP 1 LAST PATH I250
J 2
(2100 2225);
DISPLAY 0.978723 (2100 2225);
PAINT WHITE (2100 2225);
DISPLAY INVISIBLE (2100 2225);
FORCEPROP 2 LAST SEC_TYPE 0402V
J 0
(2100 2275);
DISPLAY 1.021277 (2100 2275);
PAINT ORANGE (2100 2275);
DISPLAY INVISIBLE (2100 2275);
FORCEADD GND..1
(2150 1850);
FORCEPROP 3 LASTPIN (2150 1900) SIG_NAME GND\g
J 0
(2160 1910);
DISPLAY 0.659574 (2160 1910);
PAINT MONO (2160 1910);
DISPLAY INVISIBLE (2160 1910);
FORCEPROP 2 LAST ROOM DEBUG
J 0
(1675 1925);
DISPLAY 1.617021 (1675 1925);
PAINT WHITE (1675 1925);
DISPLAY INVISIBLE (1675 1925);
FORCEPROP 2 LAST BOM_COST DEBUG
J 0
(1675 1975);
DISPLAY 1.617021 (1675 1975);
PAINT WHITE (1675 1975);
DISPLAY INVISIBLE (1675 1975);
FORCEPROP 1 LAST BODY_TYPE PLUMBING
J 0
(2105 1807);
DISPLAY 0.340426 (2105 1807);
PAINT GREEN (2105 1807);
DISPLAY INVISIBLE (2105 1807);
FORCEPROP 1 LAST VOLTAGE 0.0V
J 0
(2105 1807);
DISPLAY 0.340426 (2105 1807);
PAINT SKYBLUE (2105 1807);
DISPLAY INVISIBLE (2105 1807);
FORCEPROP 2 LAST CDS_LIB mstr_symbols
J 0
(2150 1850);
PAINT ORANGE (2150 1850);
DISPLAY INVISIBLE (2150 1850);
FORCEPROP 1 LAST HDL_POWER GND
J 0
(2150 2000);
PAINT GREEN (2150 2000);
DISPLAY INVISIBLE (2150 2000);
FORCEPROP 1 LAST SIZE 1B
J 0
(2225 1800);
DISPLAY 1.893617 (2225 1800);
PAINT GREEN (2225 1800);
DISPLAY INVISIBLE (2225 1800);
FORCEPROP 1 LAST PATH I251
J 0
(2225 1850);
DISPLAY 0.872340 (2225 1850);
PAINT AQUA (2225 1850);
DISPLAY INVISIBLE (2225 1850);
FORCEADD NC7SB3157..1
R 2
(-2125 2325);
FORCEPROP 2 LASTPIN (-2475 2175) $PN 2
J 2
(-2485 2185);
DISPLAY 0.617021 (-2485 2185);
PAINT ORANGE (-2485 2185);
FORCEPROP 2 LASTPIN (-2475 2325) $PN 4
J 2
(-2485 2335);
DISPLAY 0.617021 (-2485 2335);
PAINT ORANGE (-2485 2335);
FORCEPROP 1 LAST PACK_TYPE SMLF
J 2
(-1950 2075);
DISPLAY 0.617021 (-1950 2075);
PAINT SKYBLUE (-1950 2075);
FORCEPROP 1 LAST PART_NUMBER C99406-001
J 2
(-1825 2550);
DISPLAY 0.617021 (-1825 2550);
PAINT BLUE (-1825 2550);
FORCEPROP 1 LAST MATERIAL IC
J 2
(-1825 2075);
DISPLAY 0.617021 (-1825 2075);
PAINT SKYBLUE (-1825 2075);
FORCEPROP 2 LASTPIN (-1775 2475) $PN 6
J 0
(-1765 2485);
DISPLAY 0.617021 (-1765 2485);
PAINT ORANGE (-1765 2485);
FORCEPROP 2 LASTPIN (-1775 2175) $PN 5
J 0
(-1765 2185);
DISPLAY 0.617021 (-1765 2185);
PAINT ORANGE (-1765 2185);
FORCEPROP 2 LASTPIN (-1775 2275) $PN 1
J 0
(-1765 2285);
DISPLAY 0.617021 (-1765 2285);
PAINT ORANGE (-1765 2285);
FORCEPROP 2 LASTPIN (-1775 2375) $PN 3
J 0
(-1765 2385);
DISPLAY 0.617021 (-1765 2385);
PAINT ORANGE (-1765 2385);
FORCEPROP 1 LAST LOCATION U2M1
J 2
(-1825 2600);
DISPLAY 0.617021 (-1825 2600);
PAINT AQUA (-1825 2600);
FORCEPROP 1 LAST PATH I255
J 2
(-2200 2075);
DISPLAY 0.851064 (-2200 2075);
PAINT WHITE (-2200 2075);
DISPLAY INVISIBLE (-2200 2075);
FORCEPROP 2 LAST CDS_LIB mstr_analog
J 0
(-2125 2325);
PAINT MONO (-2125 2325);
DISPLAY INVISIBLE (-2125 2325);
FORCEPROP 2 LAST BOM_COST DEBUG
J 0
(-1825 2700);
DISPLAY 1.617021 (-1825 2700);
PAINT WHITE (-1825 2700);
DISPLAY INVISIBLE (-1825 2700);
FORCEPROP 2 LAST SEC_TYPE SMLF
J 0
(-1825 2650);
DISPLAY 1.021277 (-1825 2650);
PAINT ORANGE (-1825 2650);
DISPLAY INVISIBLE (-1825 2650);
FORCEPROP 2 LAST SEC 1
J 0
(-1825 2650);
DISPLAY 0.680851 (-1825 2650);
PAINT MONO (-1825 2650);
DISPLAY INVISIBLE (-1825 2650);
FORCEPROP 2 LAST ROOM DEBUG
J 0
(-1825 2650);
DISPLAY 1.617021 (-1825 2650);
PAINT WHITE (-1825 2650);
DISPLAY INVISIBLE (-1825 2650);
FORCEADD OFFPAGE..4
(-1100 2475);
FORCEPROP 2 LAST $XR0 191 
J 0
(-914 2475);
DISPLAY 0.638298 (-914 2475);
PAINT MONO (-914 2475);
FORCEPROP 1 LAST COMMENT_BODY TRUE
J 0
(-1125 2375);
DISPLAY 0.872340 (-1125 2375);
PAINT GREEN (-1125 2375);
DISPLAY INVISIBLE (-1125 2375);
FORCEPROP 2 LAST CDS_LIB mstr_standard
J 0
(-1100 2475);
PAINT MONO (-1100 2475);
DISPLAY INVISIBLE (-1100 2475);
FORCEPROP 1 LAST OFFPAGE TRUE
J 0
(-775 2350);
DISPLAY 0.872340 (-775 2350);
PAINT GREEN (-775 2350);
DISPLAY INVISIBLE (-775 2350);
FORCEPROP 2 LAST PATH I256
J 0
(-325 2525);
DISPLAY 1.021277 (-325 2525);
PAINT ORANGE (-325 2525);
DISPLAY INVISIBLE (-325 2525);
FORCEADD OFFPAGE..4
(-1100 2375);
FORCEPROP 2 LAST $XR0 113 
J 0
(-914 2375);
DISPLAY 0.638298 (-914 2375);
PAINT MONO (-914 2375);
FORCEPROP 2 LAST $XR1 63 
J 0
(-794 2375);
DISPLAY 0.638298 (-794 2375);
PAINT MONO (-794 2375);
FORCEPROP 1 LAST COMMENT_BODY TRUE
J 0
(-1125 2275);
DISPLAY 0.872340 (-1125 2275);
PAINT GREEN (-1125 2275);
DISPLAY INVISIBLE (-1125 2275);
FORCEPROP 2 LAST CDS_LIB mstr_standard
J 0
(-1100 2375);
PAINT MONO (-1100 2375);
DISPLAY INVISIBLE (-1100 2375);
FORCEPROP 1 LAST OFFPAGE TRUE
J 0
(-775 2250);
DISPLAY 0.872340 (-775 2250);
PAINT GREEN (-775 2250);
DISPLAY INVISIBLE (-775 2250);
FORCEPROP 2 LAST PATH I257
J 0
(-900 2425);
DISPLAY 1.021277 (-900 2425);
PAINT ORANGE (-900 2425);
DISPLAY INVISIBLE (-900 2425);
FORCEADD OFFPAGE..4
(-1100 2275);
FORCEPROP 2 LAST $XR0 113 
J 0
(-914 2275);
DISPLAY 0.638298 (-914 2275);
PAINT MONO (-914 2275);
FORCEPROP 2 LAST $XR1 29 
J 0
(-794 2275);
DISPLAY 0.638298 (-794 2275);
PAINT MONO (-794 2275);
FORCEPROP 1 LAST COMMENT_BODY TRUE
J 0
(-1125 2175);
DISPLAY 0.872340 (-1125 2175);
PAINT GREEN (-1125 2175);
DISPLAY INVISIBLE (-1125 2175);
FORCEPROP 2 LAST CDS_LIB mstr_standard
J 0
(-1100 2275);
PAINT MONO (-1100 2275);
DISPLAY INVISIBLE (-1100 2275);
FORCEPROP 1 LAST OFFPAGE TRUE
J 0
(-775 2150);
DISPLAY 0.872340 (-775 2150);
PAINT GREEN (-775 2150);
DISPLAY INVISIBLE (-775 2150);
FORCEPROP 2 LAST PATH I258
J 0
(-800 2325);
DISPLAY 1.021277 (-800 2325);
PAINT ORANGE (-800 2325);
DISPLAY INVISIBLE (-800 2325);
FORCEADD P3V3_STBY..1
(-1275 2100);
FORCEPROP 3 LASTPIN (-1275 2050) SIG_NAME P3V3_STBY\g
J 0
(-1265 2060);
DISPLAY 0.659574 (-1265 2060);
PAINT MONO (-1265 2060);
DISPLAY INVISIBLE (-1265 2060);
FORCEPROP 1 LAST HDL_POWER P3V3_STBY
J 0
(-1575 1975);
DISPLAY 0.872340 (-1575 1975);
PAINT ORANGE (-1575 1975);
DISPLAY INVISIBLE (-1575 1975);
FORCEPROP 1 LAST BODY_TYPE PLUMBING
J 0
(-1320 2057);
DISPLAY 0.340426 (-1320 2057);
PAINT GREEN (-1320 2057);
DISPLAY INVISIBLE (-1320 2057);
FORCEPROP 1 LAST VOLTAGE 3.3V
J 0
(-1320 2057);
DISPLAY 0.340426 (-1320 2057);
PAINT SKYBLUE (-1320 2057);
DISPLAY INVISIBLE (-1320 2057);
FORCEPROP 1 LAST SIZE 1B
J 0
(-1230 2122);
DISPLAY 0.340426 (-1230 2122);
PAINT GREEN (-1230 2122);
DISPLAY INVISIBLE (-1230 2122);
FORCEPROP 2 LAST CDS_LIB mstr_symbols
J 0
(-1275 2100);
PAINT ORANGE (-1275 2100);
DISPLAY INVISIBLE (-1275 2100);
FORCEPROP 1 LAST PATH I259
J 0
(-1230 2102);
DISPLAY 0.340426 (-1230 2102);
PAINT GREEN (-1230 2102);
DISPLAY INVISIBLE (-1230 2102);
FORCEADD GND..1
(-1275 1500);
FORCEPROP 3 LASTPIN (-1275 1550) SIG_NAME GND\g
J 0
(-1265 1560);
DISPLAY 0.659574 (-1265 1560);
PAINT MONO (-1265 1560);
DISPLAY INVISIBLE (-1265 1560);
FORCEPROP 2 LAST ROOM DEBUG
J 0
(-1750 1575);
DISPLAY 1.617021 (-1750 1575);
PAINT WHITE (-1750 1575);
DISPLAY INVISIBLE (-1750 1575);
FORCEPROP 2 LAST BOM_COST DEBUG
J 0
(-1750 1625);
DISPLAY 1.617021 (-1750 1625);
PAINT WHITE (-1750 1625);
DISPLAY INVISIBLE (-1750 1625);
FORCEPROP 1 LAST BODY_TYPE PLUMBING
J 0
(-1320 1457);
DISPLAY 0.340426 (-1320 1457);
PAINT GREEN (-1320 1457);
DISPLAY INVISIBLE (-1320 1457);
FORCEPROP 1 LAST SIZE 1B
J 0
(-1200 1450);
DISPLAY 1.893617 (-1200 1450);
PAINT GREEN (-1200 1450);
DISPLAY INVISIBLE (-1200 1450);
FORCEPROP 1 LAST VOLTAGE 0.0V
J 0
(-1320 1457);
DISPLAY 0.340426 (-1320 1457);
PAINT SKYBLUE (-1320 1457);
DISPLAY INVISIBLE (-1320 1457);
FORCEPROP 1 LAST PATH I261
J 0
(-1200 1500);
DISPLAY 0.872340 (-1200 1500);
PAINT AQUA (-1200 1500);
DISPLAY INVISIBLE (-1200 1500);
FORCEPROP 2 LAST CDS_LIB mstr_symbols
J 0
(-1275 1500);
PAINT MONO (-1275 1500);
DISPLAY INVISIBLE (-1275 1500);
FORCEPROP 1 LAST HDL_POWER GND
J 0
(-1275 1650);
PAINT GREEN (-1275 1650);
DISPLAY INVISIBLE (-1275 1650);
FORCEADD GND..1
(-2550 2025);
FORCEPROP 3 LASTPIN (-2550 2075) SIG_NAME GND\g
J 0
(-2540 2085);
DISPLAY 0.659574 (-2540 2085);
PAINT MONO (-2540 2085);
DISPLAY INVISIBLE (-2540 2085);
FORCEPROP 1 LAST BODY_TYPE PLUMBING
J 0
(-2595 1982);
DISPLAY 0.340426 (-2595 1982);
PAINT GREEN (-2595 1982);
DISPLAY INVISIBLE (-2595 1982);
FORCEPROP 1 LAST VOLTAGE 0.0V
J 0
(-2595 1982);
DISPLAY 0.340426 (-2595 1982);
PAINT SKYBLUE (-2595 1982);
DISPLAY INVISIBLE (-2595 1982);
FORCEPROP 1 LAST SIZE 1B
J 0
(-2475 1975);
DISPLAY 0.872340 (-2475 1975);
PAINT AQUA (-2475 1975);
DISPLAY INVISIBLE (-2475 1975);
FORCEPROP 1 LAST PATH I263
J 0
(-2475 2025);
DISPLAY 0.872340 (-2475 2025);
PAINT AQUA (-2475 2025);
DISPLAY INVISIBLE (-2475 2025);
FORCEPROP 2 LAST CDS_LIB mstr_symbols
J 0
(-2550 2025);
PAINT MONO (-2550 2025);
DISPLAY INVISIBLE (-2550 2025);
FORCEPROP 1 LAST HDL_POWER GND
J 0
(-2550 2175);
DISPLAY 0.872340 (-2550 2175);
PAINT GREEN (-2550 2175);
DISPLAY INVISIBLE (-2550 2175);
FORCEADD OFFPAGE..5
(-3050 2325);
FORCEPROP 2 LAST $XR0 113 
J 0
(-3305 2325);
DISPLAY 0.638298 (-3305 2325);
PAINT MONO (-3305 2325);
FORCEPROP 2 LAST PATH I264
J 0
(-3325 2375);
DISPLAY 1.021277 (-3325 2375);
PAINT ORANGE (-3325 2375);
DISPLAY INVISIBLE (-3325 2375);
FORCEPROP 1 LAST COMMENT_BODY TRUE
J 0
(-2950 2250);
DISPLAY 0.872340 (-2950 2250);
PAINT GREEN (-2950 2250);
DISPLAY INVISIBLE (-2950 2250);
FORCEPROP 1 LAST OFFPAGE TRUE
J 0
(-2725 2200);
DISPLAY 0.872340 (-2725 2200);
PAINT GREEN (-2725 2200);
DISPLAY INVISIBLE (-2725 2200);
FORCEPROP 2 LAST CDS_LIB mstr_standard
J 0
(-3050 2325);
PAINT MONO (-3050 2325);
DISPLAY INVISIBLE (-3050 2325);
FORCEADD CAP_A..1
R 2
(-1275 1825);
FORCEPROP 1 LAST PART_NUMBER A36096-045
J 2
(-1325 1675);
DISPLAY 0.617021 (-1325 1675);
PAINT BLUE (-1325 1675);
FORCEPROP 1 LASTPIN (-1275 1925) $PN 1
J 2
(-1285 1905);
DISPLAY 0.617021 (-1285 1905);
PAINT ORANGE (-1285 1905);
FORCEPROP 1 LASTPIN (-1275 1725) $PN 2
J 2
(-1285 1705);
DISPLAY 0.617021 (-1285 1705);
PAINT ORANGE (-1285 1705);
FORCEPROP 1 LAST VOLTAGE 25V
J 2
(-1325 1825);
DISPLAY 0.617021 (-1325 1825);
PAINT SKYBLUE (-1325 1825);
FORCEPROP 1 LAST MATERIAL X7R
J 2
(-1325 1725);
DISPLAY 0.617021 (-1325 1725);
PAINT SKYBLUE (-1325 1725);
FORCEPROP 1 LAST TOLERANCE 10%
J 2
(-1325 1775);
DISPLAY 0.617021 (-1325 1775);
PAINT SKYBLUE (-1325 1775);
FORCEPROP 1 LAST PACK_TYPE 0402V
J 2
(-1325 1625);
DISPLAY 0.617021 (-1325 1625);
PAINT SKYBLUE (-1325 1625);
FORCEPROP 1 LAST LOCATION C1M34
J 2
(-1325 1925);
DISPLAY 0.617021 (-1325 1925);
PAINT AQUA (-1325 1925);
FORCEPROP 1 LAST VALUE 0.01UF
J 2
(-1325 1875);
DISPLAY 0.617021 (-1325 1875);
PAINT SKYBLUE (-1325 1875);
FORCEPROP 2 LAST BOM_COST DEBUG
J 0
(-1325 1975);
DISPLAY 1.617021 (-1325 1975);
PAINT WHITE (-1325 1975);
DISPLAY INVISIBLE (-1325 1975);
FORCEPROP 2 LAST CDS_SEC 1
J 0
(-1325 1975);
PAINT ORANGE (-1325 1975);
DISPLAY INVISIBLE (-1325 1975);
FORCEPROP 1 LAST PATH I265
J 2
(-1325 1975);
DISPLAY 0.978723 (-1325 1975);
PAINT WHITE (-1325 1975);
DISPLAY INVISIBLE (-1325 1975);
FORCEPROP 2 LAST ROOM DEBUG
J 2
(-1325 1975);
DISPLAY 1.617021 (-1325 1975);
PAINT WHITE (-1325 1975);
DISPLAY INVISIBLE (-1325 1975);
FORCEPROP 2 LAST CDS_LIB dev_discrete
J 0
(-1275 1825);
PAINT ORANGE (-1275 1825);
DISPLAY INVISIBLE (-1275 1825);
FORCEPROP 2 LAST SEC 1
J 0
(-1325 2025);
DISPLAY 0.680851 (-1325 2025);
PAINT MONO (-1325 2025);
DISPLAY INVISIBLE (-1325 2025);
FORCEPROP 2 LAST SEC_TYPE 0402V
J 0
(-1325 2025);
DISPLAY 1.021277 (-1325 2025);
PAINT ORANGE (-1325 2025);
DISPLAY INVISIBLE (-1325 2025);
FORCEADD CAP_A..1
R 2
(-1600 1825);
FORCEPROP 1 LAST VALUE 0.01UF
J 2
(-1650 1875);
DISPLAY 0.617021 (-1650 1875);
PAINT SKYBLUE (-1650 1875);
FORCEPROP 1 LAST PART_NUMBER A36096-045
J 2
(-1650 1675);
DISPLAY 0.617021 (-1650 1675);
PAINT BLUE (-1650 1675);
FORCEPROP 1 LAST LOCATION C1M35
J 2
(-1650 1925);
DISPLAY 0.617021 (-1650 1925);
PAINT AQUA (-1650 1925);
FORCEPROP 1 LAST PACK_TYPE 0402V
J 2
(-1650 1625);
DISPLAY 0.617021 (-1650 1625);
PAINT SKYBLUE (-1650 1625);
FORCEPROP 1 LAST MATERIAL X7R
J 2
(-1650 1725);
DISPLAY 0.617021 (-1650 1725);
PAINT SKYBLUE (-1650 1725);
FORCEPROP 1 LASTPIN (-1600 1725) $PN 2
J 2
(-1610 1705);
DISPLAY 0.617021 (-1610 1705);
PAINT ORANGE (-1610 1705);
FORCEPROP 1 LAST TOLERANCE 10%
J 2
(-1650 1775);
DISPLAY 0.617021 (-1650 1775);
PAINT SKYBLUE (-1650 1775);
FORCEPROP 1 LAST VOLTAGE 25V
J 2
(-1650 1825);
DISPLAY 0.617021 (-1650 1825);
PAINT SKYBLUE (-1650 1825);
FORCEPROP 1 LASTPIN (-1600 1925) $PN 1
J 2
(-1610 1905);
DISPLAY 0.617021 (-1610 1905);
PAINT ORANGE (-1610 1905);
FORCEPROP 2 LAST CDS_LIB dev_discrete
J 0
(-1600 1825);
PAINT ORANGE (-1600 1825);
DISPLAY INVISIBLE (-1600 1825);
FORCEPROP 2 LAST BOM_COST DEBUG
J 0
(-1650 1975);
DISPLAY 1.617021 (-1650 1975);
PAINT WHITE (-1650 1975);
DISPLAY INVISIBLE (-1650 1975);
FORCEPROP 2 LAST CDS_SEC 1
J 0
(-1650 1975);
PAINT ORANGE (-1650 1975);
DISPLAY INVISIBLE (-1650 1975);
FORCEPROP 1 LAST PATH I266
J 2
(-1650 1975);
DISPLAY 0.978723 (-1650 1975);
PAINT WHITE (-1650 1975);
DISPLAY INVISIBLE (-1650 1975);
FORCEPROP 2 LAST ROOM DEBUG
J 2
(-1650 1975);
DISPLAY 1.617021 (-1650 1975);
PAINT WHITE (-1650 1975);
DISPLAY INVISIBLE (-1650 1975);
FORCEPROP 2 LAST SEC 1
J 0
(-1650 2025);
DISPLAY 0.680851 (-1650 2025);
PAINT MONO (-1650 2025);
DISPLAY INVISIBLE (-1650 2025);
FORCEPROP 2 LAST SEC_TYPE 0402V
J 0
(-1650 2025);
DISPLAY 1.021277 (-1650 2025);
PAINT ORANGE (-1650 2025);
DISPLAY INVISIBLE (-1650 2025);
FORCEADD CAP_A..1
R 2
(3025 3650);
FORCEPROP 1 LASTPIN (3025 3750) $PN 1
J 2
(3015 3730);
DISPLAY 0.617021 (3015 3730);
PAINT ORANGE (3015 3730);
FORCEPROP 1 LASTPIN (3025 3550) $PN 2
J 2
(3015 3530);
DISPLAY 0.617021 (3015 3530);
PAINT ORANGE (3015 3530);
FORCEPROP 1 LAST LOCATION C1L20
J 2
(2975 3750);
DISPLAY 0.617021 (2975 3750);
PAINT AQUA (2975 3750);
FORCEPROP 1 LAST PART_NUMBER A36096-045
J 2
(2975 3500);
DISPLAY 0.617021 (2975 3500);
PAINT BLUE (2975 3500);
FORCEPROP 1 LAST VALUE 0.01UF
J 2
(2975 3700);
DISPLAY 0.617021 (2975 3700);
PAINT SKYBLUE (2975 3700);
FORCEPROP 1 LAST TOLERANCE 10%
J 2
(2975 3600);
DISPLAY 0.617021 (2975 3600);
PAINT SKYBLUE (2975 3600);
FORCEPROP 1 LAST PACK_TYPE 0402V
J 2
(2975 3450);
DISPLAY 0.617021 (2975 3450);
PAINT SKYBLUE (2975 3450);
FORCEPROP 1 LAST VOLTAGE 25V
J 2
(2975 3650);
DISPLAY 0.617021 (2975 3650);
PAINT SKYBLUE (2975 3650);
FORCEPROP 1 LAST MATERIAL X7R
J 2
(2975 3550);
DISPLAY 0.617021 (2975 3550);
PAINT SKYBLUE (2975 3550);
FORCEPROP 2 LAST SEC_TYPE 0402V
J 0
(2975 3850);
DISPLAY 1.021277 (2975 3850);
PAINT ORANGE (2975 3850);
DISPLAY INVISIBLE (2975 3850);
FORCEPROP 2 LAST SEC 1
J 0
(2975 3850);
DISPLAY 0.680851 (2975 3850);
PAINT MONO (2975 3850);
DISPLAY INVISIBLE (2975 3850);
FORCEPROP 2 LAST BOM_COST DEBUG
J 0
(2975 3800);
DISPLAY 1.617021 (2975 3800);
PAINT WHITE (2975 3800);
DISPLAY INVISIBLE (2975 3800);
FORCEPROP 2 LAST CDS_SEC 1
J 0
(2975 3800);
PAINT ORANGE (2975 3800);
DISPLAY INVISIBLE (2975 3800);
FORCEPROP 1 LAST PATH I267
J 2
(2975 3800);
DISPLAY 0.978723 (2975 3800);
PAINT WHITE (2975 3800);
DISPLAY INVISIBLE (2975 3800);
FORCEPROP 2 LAST ROOM DEBUG
J 2
(2975 3800);
DISPLAY 1.617021 (2975 3800);
PAINT WHITE (2975 3800);
DISPLAY INVISIBLE (2975 3800);
FORCEPROP 2 LAST CDS_LIB dev_discrete
J 0
(3025 3650);
PAINT ORANGE (3025 3650);
DISPLAY INVISIBLE (3025 3650);
FORCEADD GND..1
(3025 3450);
FORCEPROP 3 LASTPIN (3025 3500) SIG_NAME GND\g
J 0
(3035 3510);
DISPLAY 0.659574 (3035 3510);
PAINT MONO (3035 3510);
DISPLAY INVISIBLE (3035 3510);
FORCEPROP 1 LAST HDL_POWER GND
J 0
(3025 3600);
PAINT GREEN (3025 3600);
DISPLAY INVISIBLE (3025 3600);
FORCEPROP 1 LAST PATH I268
J 0
(3100 3450);
DISPLAY 0.872340 (3100 3450);
PAINT AQUA (3100 3450);
DISPLAY INVISIBLE (3100 3450);
FORCEPROP 1 LAST SIZE 1B
J 0
(3100 3400);
DISPLAY 1.893617 (3100 3400);
PAINT GREEN (3100 3400);
DISPLAY INVISIBLE (3100 3400);
FORCEPROP 1 LAST BODY_TYPE PLUMBING
J 0
(2980 3407);
DISPLAY 0.340426 (2980 3407);
PAINT GREEN (2980 3407);
DISPLAY INVISIBLE (2980 3407);
FORCEPROP 2 LAST CDS_LIB mstr_symbols
J 0
(3025 3450);
PAINT ORANGE (3025 3450);
DISPLAY INVISIBLE (3025 3450);
FORCEPROP 1 LAST VOLTAGE 0.0V
J 0
(2980 3407);
DISPLAY 0.340426 (2980 3407);
PAINT SKYBLUE (2980 3407);
DISPLAY INVISIBLE (2980 3407);
FORCEPROP 2 LAST BOM_COST DEBUG
J 0
(2550 3575);
DISPLAY 1.617021 (2550 3575);
PAINT WHITE (2550 3575);
DISPLAY INVISIBLE (2550 3575);
FORCEPROP 2 LAST ROOM DEBUG
J 0
(2550 3525);
DISPLAY 1.617021 (2550 3525);
PAINT WHITE (2550 3525);
DISPLAY INVISIBLE (2550 3525);
FORCEADD P3V3_STBY..1
(3025 3850);
FORCEPROP 3 LASTPIN (3025 3800) SIG_NAME P3V3_STBY\g
J 0
(3035 3810);
DISPLAY 0.659574 (3035 3810);
PAINT MONO (3035 3810);
DISPLAY INVISIBLE (3035 3810);
FORCEPROP 1 LAST SIZE 1B
J 0
(3070 3872);
DISPLAY 0.340426 (3070 3872);
PAINT GREEN (3070 3872);
DISPLAY INVISIBLE (3070 3872);
FORCEPROP 2 LAST CDS_LIB mstr_symbols
J 0
(3025 3850);
PAINT ORANGE (3025 3850);
DISPLAY INVISIBLE (3025 3850);
FORCEPROP 1 LAST PATH I269
J 0
(3070 3852);
DISPLAY 0.340426 (3070 3852);
PAINT GREEN (3070 3852);
DISPLAY INVISIBLE (3070 3852);
FORCEPROP 1 LAST VOLTAGE 3.3V
J 0
(2980 3807);
DISPLAY 0.340426 (2980 3807);
PAINT SKYBLUE (2980 3807);
DISPLAY INVISIBLE (2980 3807);
FORCEPROP 1 LAST BODY_TYPE PLUMBING
J 0
(2980 3807);
DISPLAY 0.340426 (2980 3807);
PAINT GREEN (2980 3807);
DISPLAY INVISIBLE (2980 3807);
FORCEPROP 1 LAST HDL_POWER P3V3_STBY
J 0
(2725 3725);
DISPLAY 0.872340 (2725 3725);
PAINT ORANGE (2725 3725);
DISPLAY INVISIBLE (2725 3725);
FORCEADD CAD_NOTE..1
(2800 3275);
FORCEPROP 0 LAST L1 PLACE U4R1 AND R4R6 NEAR CPU0 PKG PIN
J 0
(2650 3150);
DISPLAY 0.808511 (2650 3150);
PAINT ORANGE (2650 3150);
FORCEPROP 2 LAST CDS_LIB mstr_symbols
J 0
(2800 3275);
PAINT ORANGE (2800 3275);
DISPLAY INVISIBLE (2800 3275);
FORCEPROP 1 LAST COMMENT_BODY TRUE
J 0
(2825 3375);
DISPLAY 0.978723 (2825 3375);
PAINT ORANGE (2825 3375);
DISPLAY INVISIBLE (2825 3375);
FORCEADD CAD_NOTE..1
(2800 2750);
FORCEPROP 0 LAST L1 PLACE U1M5 AND R1M22 NEAR CPU1 PKG PIN
J 0
(2650 2625);
DISPLAY 0.808511 (2650 2625);
PAINT ORANGE (2650 2625);
FORCEPROP 2 LAST CDS_LIB mstr_symbols
J 0
(2800 2750);
PAINT ORANGE (2800 2750);
DISPLAY INVISIBLE (2800 2750);
FORCEPROP 1 LAST COMMENT_BODY TRUE
J 0
(2825 2850);
DISPLAY 0.978723 (2825 2850);
PAINT ORANGE (2825 2850);
DISPLAY INVISIBLE (2825 2850);
FORCEADD CAD_NOTE..1
(3350 3725);
FORCEPROP 0 LAST L1 PLACE CAP NEAR 74CBTLV1G125
J 0
(3200 3600);
DISPLAY 0.808511 (3200 3600);
PAINT ORANGE (3200 3600);
FORCEPROP 1 LAST COMMENT_BODY TRUE
J 0
(3375 3825);
DISPLAY 0.978723 (3375 3825);
PAINT ORANGE (3375 3825);
DISPLAY INVISIBLE (3375 3825);
FORCEPROP 2 LAST CDS_LIB mstr_symbols
J 0
(3350 3725);
PAINT ORANGE (3350 3725);
DISPLAY INVISIBLE (3350 3725);
FORCEADD DESIGN_NOTE..1
(-3325 575);
FORCEPROP 0 LAST L1 MCP JTAG FOR DEBUG USE ONLY
J 0
(-3525 375);
DISPLAY 2.000000 (-3525 375);
PAINT ORANGE (-3525 375);
FORCEPROP 1 LAST COMMENT_BODY TRUE
J 0
(-3300 675);
DISPLAY 0.978723 (-3300 675);
PAINT ORANGE (-3300 675);
DISPLAY INVISIBLE (-3300 675);
FORCEPROP 2 LAST CDS_LIB mstr_symbols
J 0
(-3325 575);
PAINT ORANGE (-3325 575);
DISPLAY INVISIBLE (-3325 575);
FORCEADD DNS..2
(1405 4220);
PAINT RED (1405 4220);
FORCEPROP 1 LAST COMMENT_BODY TRUE
R 1
J 0
(1480 3995);
DISPLAY 0.872340 (1480 3995);
PAINT GREEN (1480 3995);
DISPLAY INVISIBLE (1480 3995);
FORCEPROP 2 LAST CDS_LIB mstr_misc
J 0
(1405 4220);
PAINT ORANGE (1405 4220);
DISPLAY INVISIBLE (1405 4220);
FORCEADD CAD_NOTE..1
(-1925 1325);
FORCEPROP 0 LAST L1 PLACE CAP NEAR 74CBTLV1G125
J 0
(-2075 1200);
DISPLAY 0.808511 (-2075 1200);
PAINT ORANGE (-2075 1200);
FORCEPROP 2 LAST CDS_LIB mstr_symbols
J 0
(-1925 1325);
PAINT MONO (-1925 1325);
DISPLAY INVISIBLE (-1925 1325);
FORCEPROP 1 LAST COMMENT_BODY TRUE
J 0
(-1900 1425);
DISPLAY 0.978723 (-1900 1425);
PAINT ORANGE (-1900 1425);
DISPLAY INVISIBLE (-1900 1425);
FORCEADD CAD_NOTE..1
(2000 1675);
FORCEPROP 0 LAST L2 INCHES OF CORRESPONDING RESISTOR
J 0
(1850 1475);
DISPLAY 0.808511 (1850 1475);
PAINT ORANGE (1850 1475);
FORCEPROP 0 LAST L1 PLACE DECOUPLING CAPS WITHIN 0.5
J 0
(1850 1550);
DISPLAY 0.808511 (1850 1550);
PAINT ORANGE (1850 1550);
FORCEPROP 2 LAST CDS_LIB mstr_symbols
J 0
(2000 1675);
PAINT ORANGE (2000 1675);
DISPLAY INVISIBLE (2000 1675);
FORCEPROP 1 LAST COMMENT_BODY TRUE
J 0
(2025 1775);
DISPLAY 0.978723 (2025 1775);
PAINT ORANGE (2025 1775);
DISPLAY INVISIBLE (2025 1775);
FORCEADD CAD_NOTE..1
(2800 2150);
FORCEPROP 0 LAST L1 PLACE U6M1 AND R6M8 NEAR CPU1 PKG PIN
J 0
(2650 2025);
DISPLAY 0.808511 (2650 2025);
PAINT ORANGE (2650 2025);
FORCEPROP 2 LAST CDS_LIB mstr_symbols
J 0
(2800 2150);
PAINT ORANGE (2800 2150);
DISPLAY INVISIBLE (2800 2150);
FORCEPROP 1 LAST COMMENT_BODY TRUE
J 0
(2825 2250);
DISPLAY 0.978723 (2825 2250);
PAINT ORANGE (2825 2250);
DISPLAY INVISIBLE (2825 2250);
FORCEADD BOM_NOTE..1
(425 4275);
FORCEPROP 0 LAST L1 R1M23 MUST BE UNPOPPED IN DEBUG
J 0
(275 4150);
DISPLAY 0.808511 (275 4150);
PAINT ORANGE (275 4150);
FORCEPROP 0 LAST L2 R1M23 MUST BE POPPED IN VOLUME
J 0
(275 4100);
DISPLAY 0.808511 (275 4100);
PAINT ORANGE (275 4100);
FORCEPROP 1 LAST COMMENT_BODY TRUE
J 0
(450 4375);
DISPLAY 0.978723 (450 4375);
PAINT ORANGE (450 4375);
DISPLAY INVISIBLE (450 4375);
FORCEPROP 2 LAST CDS_LIB mstr_symbols
J 0
(425 4275);
PAINT ORANGE (425 4275);
DISPLAY INVISIBLE (425 4275);
FORCEADD DESIGN_NOTE..1
(-2625 4925);
FORCEPROP 0 LAST L1 TCK AND TMS SERIES RES VALUE TBD
J 0
(-2825 4800);
DISPLAY 0.808511 (-2825 4800);
PAINT ORANGE (-2825 4800);
FORCEPROP 1 LAST COMMENT_BODY TRUE
J 0
(-2600 5025);
DISPLAY 0.978723 (-2600 5025);
PAINT ORANGE (-2600 5025);
DISPLAY INVISIBLE (-2600 5025);
FORCEPROP 2 LAST CDS_LIB mstr_symbols
J 0
(-2625 4925);
PAINT ORANGE (-2625 4925);
DISPLAY INVISIBLE (-2625 4925);
FORCEADD BOM_NOTE..1
(2050 1200);
FORCEPROP 0 LAST L1 R1M21 MUST BE DEPOPPED IN VOLUME
J 0
(1925 1075);
DISPLAY 0.808511 (1925 1075);
PAINT ORANGE (1925 1075);
FORCEPROP 1 LAST COMMENT_BODY TRUE
J 0
(2075 1300);
DISPLAY 0.978723 (2075 1300);
PAINT ORANGE (2075 1300);
DISPLAY INVISIBLE (2075 1300);
FORCEPROP 2 LAST CDS_LIB mstr_symbols
J 0
(2050 1200);
PAINT ORANGE (2050 1200);
DISPLAY INVISIBLE (2050 1200);
FORCEADD DESIGN_NOTE..1
(25 675);
FORCEPROP 0 LAST L1 ADDITIONAL LOGIC WILL BE REQUIRED
J 0
(-175 550);
DISPLAY 1.021277 (-175 550);
PAINT ORANGE (-175 550);
FORCEPROP 0 LAST L2 ON THE ADAPTER BOARD FOR RC CPU SKU TO CD CPU SKU
J 0
(-175 475);
DISPLAY 1.021277 (-175 475);
PAINT ORANGE (-175 475);
FORCEPROP 1 LAST COMMENT_BODY TRUE
J 0
(50 775);
DISPLAY 0.978723 (50 775);
PAINT ORANGE (50 775);
DISPLAY INVISIBLE (50 775);
FORCEPROP 2 LAST CDS_LIB mstr_symbols
J 0
(25 675);
PAINT ORANGE (25 675);
DISPLAY INVISIBLE (25 675);
FORCEADD INTEL_CORP_BPAGE..1
(4200 75);
FORCEPROP 1 LAST CDS_CON_LAST_MODIFIED Tue Dec 01 11:51:55 2015
J 0
(2775 400);
PAINT ORANGE (2775 400);
DISPLAY INVISIBLE (2775 400);
FORCEPROP 1 LAST CUSTOM_TXT_CDS <CURRENT_DESIGN_SHEET> OF <TOTAL_DESIGN_SHEETS>
J 0
(3700 100);
PAINT GREEN (3700 100);
FORCEPROP 1 LAST CUSTOM_TXT_CDS <CON_LAST_MODIFIED>
J 0
(2275 425);
PAINT GREEN (2275 425);
FORCEPROP 2 LAST CUSTOM_TXT_CDS <XR_PAGE_TITLE>
J 0
(-3690 5325);
DISPLAY 0.638298 (-3690 5325);
PAINT PINK (-3690 5325);
DISPLAY INVISIBLE (-3690 5325);
FORCEPROP 1 LAST SCH_TITLE MCP JTAG
J 0
(-3750 125);
DISPLAY 1.212766 (-3750 125);
PAINT YELLOW (-3750 125);
FORCEPROP 1 LAST SCH_ADDRESS3 Santa Clara, CA 95052-8119
J 0
(225 100);
DISPLAY 0.617021 (225 100);
PAINT YELLOW (225 100);
FORCEPROP 1 LAST SCH_ADDRESS2 P.O. BOX 58119
J 0
(225 150);
DISPLAY 0.617021 (225 150);
PAINT YELLOW (225 150);
FORCEPROP 1 LAST SCH_ADDRESS1 2200 Mission College Blvd.
J 0
(225 200);
DISPLAY 0.617021 (225 200);
PAINT YELLOW (225 200);
FORCEPROP 1 LAST SCH_REV 2.420
J 0
(3950 225);
DISPLAY 0.978723 (3950 225);
PAINT YELLOW (3950 225);
FORCEPROP 1 LAST SCH_DEPT BESD
J 1
(-250 175);
DISPLAY 1.212766 (-250 175);
PAINT YELLOW (-250 175);
FORCEPROP 1 LAST SCH_NUMBER H4694802
J 0
(2900 225);
DISPLAY 1.212766 (2900 225);
PAINT YELLOW (2900 225);
FORCEPROP 2 LAST PAGE_BORDER TRUE
J 0
(-3690 5325);
DISPLAY 0.638298 (-3690 5325);
PAINT PINK (-3690 5325);
DISPLAY INVISIBLE (-3690 5325);
FORCEPROP 1 LAST COMMENT_BODY TRUE
J 0
(4212 87);
DISPLAY 0.468085 (4212 87);
PAINT PEACH (4212 87);
DISPLAY INVISIBLE (4212 87);
FORCEPROP 2 LAST CDS_LIB mstr_symbols
J 0
(4200 75);
PAINT ORANGE (4200 75);
DISPLAY INVISIBLE (4200 75);
FORCEPROP 2 LAST CDS_XR_PAGE_TITLE CR-113 : @BASEBOARD_FAB2_LIB.BASEBOARD_FAB2(SCH_1):PAGE113
J 0
(-3690 5325);
DISPLAY 0.638298 (-3690 5325);
PAINT PINK (-3690 5325);
DISPLAY INVISIBLE (-3690 5325);
FORCEADD CAD_NOTE..1
(2975 4125);
FORCEPROP 0 LAST L1 PLACE U9A5 AND R9B9 NEAR CPU1 PKG PIN
J 0
(2825 4000);
DISPLAY 0.808511 (2825 4000);
PAINT ORANGE (2825 4000);
FORCEPROP 2 LAST CDS_LIB mstr_symbols
J 0
(2975 4125);
PAINT ORANGE (2975 4125);
DISPLAY INVISIBLE (2975 4125);
FORCEPROP 1 LAST COMMENT_BODY TRUE
J 0
(3000 4225);
DISPLAY 0.978723 (3000 4225);
PAINT ORANGE (3000 4225);
DISPLAY INVISIBLE (3000 4225);
WIRE 16 -1 (-2425 3375)(-2500 3375);
WIRE 16 -1 (-2500 3375)(-2500 3275);
WIRE 16 -1 (-1225 4475)(-1150 4475);
WIRE 16 -1 (-1150 4275)(-1150 4475);
WIRE 16 -1 (-1225 4275)(-1150 4275);
WIRE 16 -1 (-1150 4150)(-1150 4275);
WIRE 16 -1 (-1250 2800)(-1550 2800);
WIRE 16 -1 (-1250 2925)(-1250 2800);
WIRE 16 -1 (-1250 2775)(-1250 2800);
WIRE 16 -1 (-1550 2800)(-1550 2925);
WIRE 16 -1 (-2250 1150)(-2250 1100);
WIRE 16 -1 (-975 4500)(-975 4550);
WIRE 16 -1 (-1550 3375)(-1725 3375);
WIRE 16 -1 (-1550 3375)(-1550 3200);
WIRE 16 -1 (-1550 3125)(-1550 3200);
WIRE 16 -1 (-1250 3200)(-1550 3200);
WIRE 16 -1 (-1250 3125)(-1250 3200);
WIRE 16 -1 (-1250 3250)(-1250 3200);
WIRE 16 -1 (-2250 1400)(-2250 1350);
WIRE 16 -1 (-975 4750)(-975 4800);
WIRE 16 -1 (-975 4800)(-1100 4800);
WIRE 16 -1 (-1100 4425)(-1100 4800);
WIRE 16 -1 (-1100 4800)(-1100 4850);
WIRE 16 -1 (-1225 4425)(-1100 4425);
WIRE 16 -1 (2600 4050)(2600 4000);
WIRE 16 -1 (3925 4300)(3925 4400);
WIRE 16 -1 (3925 4400)(3825 4400);
WIRE 16 -1 (1400 4125)(1400 4000);
WIRE 16 -1 (2925 1125)(2925 1200);
WIRE 16 -1 (2925 1200)(3175 1200);
WIRE 16 -1 (3175 1125)(3175 1200);
WIRE 16 -1 (3425 1200)(3175 1200);
WIRE 16 -1 (3425 1125)(3425 1200);
WIRE 16 -1 (3575 1200)(3425 1200);
WIRE 16 -1 (3675 1200)(3575 1200);
WIRE 16 -1 (3575 1200)(3575 1225);
WIRE 16 -1 (3675 1200)(3675 1125);
WIRE 16 -1 (1350 2250)(1275 2250);
WIRE 16 -1 (1275 2450)(1275 2250);
WIRE 16 -1 (1375 3375)(1275 3375);
WIRE 16 -1 (1275 3625)(1275 3375);
WIRE 16 -1 (1350 2825)(1275 2825);
WIRE 16 -1 (1275 2825)(1275 3025);
WIRE 16 -1 (2125 3050)(2125 3100);
WIRE 16 -1 (2125 2500)(2125 2550);
WIRE 16 -1 (2150 1975)(2150 1900);
WIRE 16 -1 (-1600 2175)(-1775 2175);
WIRE 16 -1 (-1600 2175)(-1600 2000);
WIRE 16 -1 (-1600 1925)(-1600 2000);
WIRE 16 -1 (-1275 2000)(-1600 2000);
WIRE 16 -1 (-1275 1925)(-1275 2000);
WIRE 16 -1 (-1275 2050)(-1275 2000);
WIRE 16 -1 (-1600 1725)(-1600 1575);
WIRE 16 -1 (-1275 1575)(-1600 1575);
WIRE 16 -1 (-1275 1725)(-1275 1575);
WIRE 16 -1 (-1275 1550)(-1275 1575);
WIRE 16 -1 (-2475 2175)(-2550 2175);
WIRE 16 -1 (-2550 2175)(-2550 2075);
WIRE 16 -1 (3025 3550)(3025 3500);
WIRE 16 -1 (3025 3800)(3025 3750);
WIRE 16 -1 (1350 2200)(625 2200);
FORCEPROP 0 LAST SIG_NAME FM_CPU1_PKGID1
J 0
(625 2210);
DISPLAY 0.617021 (625 2210);
PAINT ORANGE (625 2210);
WIRE 16 -1 (2450 1900)(2900 1900);
FORCEPROP 2 LAST SIG_NAME JTAG_MCP_CPU1_TDI
J 0
(2500 1910);
DISPLAY 0.617021 (2500 1910);
PAINT ORANGE (2500 1910);
WIRE 16 -1 (2450 1975)(2450 1900);
WIRE 16 -1 (2475 700)(3675 700);
FORCEPROP 0 LAST SIG_NAME JTAG_MCP_TRST_N
J 0
(2475 710);
DISPLAY 0.617021 (2475 710);
PAINT ORANGE (2475 710);
WIRE 16 -1 (3675 925)(3675 700);
WIRE 16 273 (1750 1225)(1750 450);
WIRE 16 273 (25 1225)(1750 1225);
WIRE 16 273 (25 1225)(25 4975);
WIRE 16 -1 (2475 800)(3175 800);
FORCEPROP 0 LAST SIG_NAME JTAG_MCP_TMS
J 0
(2475 810);
DISPLAY 0.617021 (2475 810);
PAINT ORANGE (2475 810);
WIRE 16 -1 (3175 800)(3175 925);
WIRE 16 -1 (3425 925)(3425 750);
WIRE 16 -1 (2475 750)(3425 750);
FORCEPROP 2 LAST SIG_NAME JTAG_MCP_MUX_TDO
J 0
(2475 760);
DISPLAY 0.617021 (2475 760);
PAINT ORANGE (2475 760);
WIRE 16 -1 (2925 850)(2925 925);
WIRE 16 -1 (2925 850)(2475 850);
FORCEPROP 2 LAST SIG_NAME JTAG_MCP_MUX_TDI
J 0
(2475 860);
DISPLAY 0.617021 (2475 860);
PAINT ORANGE (2475 860);
WIRE 16 -1 (3325 4400)(2900 4400);
FORCEPROP 0 LAST SIG_NAME JTAG_MCP_TCK_R
J 0
(2940 4410);
DISPLAY 0.617021 (2940 4410);
PAINT ORANGE (2940 4410);
FORCEPROP 2 LASTPROP $XR0 113 
J 0
(2604 4410);
DISPLAY 0.638298 (2604 4410);
PAINT MONO (2604 4410);
WIRE 16 -1 (3325 4350)(2250 4350);
FORCEPROP 2 LAST SIG_NAME FM_CPU0_OR_CPU1_MCP_PRES
J 0
(2250 4360);
DISPLAY 0.617021 (2250 4360);
PAINT ORANGE (2250 4360);
WIRE 16 -1 (2600 4250)(2600 4400);
WIRE 16 -1 (2700 4400)(2600 4400);
WIRE 16 -1 (2250 4400)(2600 4400);
FORCEPROP 0 LAST SIG_NAME JTAG_MCP_TCK
J 0
(2250 4410);
DISPLAY 0.617021 (2250 4410);
PAINT ORANGE (2250 4410);
WIRE 16 -1 (1400 4325)(1400 4400);
WIRE 16 -1 (1000 4400)(1400 4400);
FORCEPROP 0 LAST SIG_NAME JTAG_MCP_TRST_N
J 0
(1000 4410);
DISPLAY 0.617021 (1000 4410);
PAINT ORANGE (1000 4410);
WIRE 16 -1 (2450 3300)(2450 3375);
WIRE 16 -1 (2450 3375)(2125 3375);
WIRE 16 -1 (2125 3375)(2125 3300);
WIRE 16 -1 (2125 3375)(1875 3375);
FORCEPROP 0 LAST SIG_NAME JTAG_MCP_CPU0_TDI_R
J 0
(1925 3385);
DISPLAY 0.617021 (1925 3385);
PAINT ORANGE (1925 3385);
FORCEPROP 2 LASTPROP $XRERR UNIQUE?
J 0
(1685 3385);
DISPLAY 0.638298 (1685 3385);
PAINT MONO (1685 3385);
DISPLAY INVISIBLE (1685 3385);
WIRE 16 -1 (2450 3025)(2450 3100);
WIRE 16 -1 (2450 3025)(2875 3025);
FORCEPROP 2 LAST SIG_NAME JTAG_MCP_CPU0_TDI
J 0
(2500 3035);
DISPLAY 0.617021 (2500 3035);
PAINT ORANGE (2500 3035);
WIRE 16 -1 (2450 2475)(2875 2475);
FORCEPROP 0 LAST SIG_NAME JTAG_MCP_TMS
J 0
(2500 2485);
DISPLAY 0.617021 (2500 2485);
PAINT ORANGE (2500 2485);
WIRE 16 -1 (2450 2475)(2450 2550);
WIRE 16 -1 (2450 2825)(2450 2750);
WIRE 16 -1 (2125 2825)(2450 2825);
WIRE 16 -1 (2125 2750)(2125 2825);
WIRE 16 -1 (1850 2825)(2125 2825);
FORCEPROP 0 LAST SIG_NAME JTAG_MCP_TMS_R1
J 0
(1900 2835);
DISPLAY 0.617021 (1900 2835);
PAINT ORANGE (1900 2835);
FORCEPROP 2 LASTPROP $XRERR UNIQUE?
J 0
(1660 2835);
DISPLAY 0.638298 (1660 2835);
PAINT MONO (1660 2835);
DISPLAY INVISIBLE (1660 2835);
WIRE 16 -1 (2450 2250)(2450 2175);
WIRE 16 -1 (2150 2250)(2450 2250);
WIRE 16 -1 (2150 2175)(2150 2250);
WIRE 16 -1 (1850 2250)(2150 2250);
FORCEPROP 0 LAST SIG_NAME JTAG_MCP_CPU1_TDI_R
J 0
(1925 2260);
DISPLAY 0.617021 (1925 2260);
PAINT ORANGE (1925 2260);
FORCEPROP 2 LASTPROP $XRERR UNIQUE?
J 0
(1685 2260);
DISPLAY 0.638298 (1685 2260);
PAINT MONO (1685 2260);
DISPLAY INVISIBLE (1685 2260);
WIRE 16 -1 (1350 2775)(625 2775);
FORCEPROP 2 LAST SIG_NAME FM_CPU0_OR_CPU1_MCP_PRES
J 0
(625 2785);
DISPLAY 0.617021 (625 2785);
PAINT ORANGE (625 2785);
WIRE 16 -1 (1375 3325)(625 3325);
FORCEPROP 2 LAST SIG_NAME FM_CPU0_PKGID1
J 0
(625 3335);
DISPLAY 0.617021 (625 3335);
PAINT ORANGE (625 3335);
WIRE 16 -1 (-1225 4325)(-600 4325);
FORCEPROP 0 LAST SIG_NAME TP_JTAG_MCP_IO8_RSVD
J 0
(-1100 4335);
DISPLAY 0.617021 (-1100 4335);
PAINT ORANGE (-1100 4335);
FORCEPROP 2 LASTPROP $XRERR UNIQUE?
J 0
(-570 4325);
DISPLAY 0.638298 (-570 4325);
PAINT MONO (-570 4325);
DISPLAY INVISIBLE (-570 4325);
WIRE 16 -1 (-600 4375)(-1225 4375);
FORCEPROP 0 LAST SIG_NAME JTAG_MCP_TRST_N
J 0
(-1100 4385);
DISPLAY 0.617021 (-1100 4385);
PAINT ORANGE (-1100 4385);
WIRE 16 -1 (-3075 4425)(-1525 4425);
FORCEPROP 0 LAST SIG_NAME JTAG_MCP_MUX_TDO
J 0
(-3075 4435);
DISPLAY 0.617021 (-3075 4435);
PAINT ORANGE (-3075 4435);
WIRE 16 -1 (-2500 4375)(-1525 4375);
FORCEPROP 2 LAST SIG_NAME JTAG_MCP_TMS_R
J 0
(-2050 4385);
DISPLAY 0.617021 (-2050 4385);
PAINT ORANGE (-2050 4385);
FORCEPROP 2 LASTPROP $XRERR UNIQUE?
J 0
(-2290 4385);
DISPLAY 0.638298 (-2290 4385);
PAINT MONO (-2290 4385);
DISPLAY INVISIBLE (-2290 4385);
WIRE 16 -1 (-1525 4275)(-2050 4275);
WIRE 16 -1 (-2050 4275)(-2050 3975);
WIRE 16 -1 (-2050 3975)(-3075 3975);
FORCEPROP 0 LAST SIG_NAME JTAG_MCP_MUX_TDI
J 0
(-3075 3985);
DISPLAY 0.617021 (-3075 3985);
PAINT ORANGE (-3075 3985);
WIRE 16 -1 (-2100 4325)(-1525 4325);
WIRE 16 -1 (-2100 4150)(-2100 4325);
WIRE 16 -1 (-2500 4150)(-2100 4150);
FORCEPROP 0 LAST SIG_NAME PWRGD_CPU0_G_R
J 0
(-2050 4335);
DISPLAY 0.617021 (-2050 4335);
PAINT ORANGE (-2050 4335);
FORCEPROP 2 LASTPROP $XRERR UNIQUE?
J 0
(-2290 4335);
DISPLAY 0.638298 (-2290 4335);
PAINT MONO (-2290 4335);
DISPLAY INVISIBLE (-2290 4335);
WIRE 16 -1 (-2100 4475)(-1525 4475);
FORCEPROP 0 LAST SIG_NAME JTAG_MCP_TCK_R
J 0
(-2050 4485);
DISPLAY 0.617021 (-2050 4485);
PAINT ORANGE (-2050 4485);
FORCEPROP 2 LASTPROP $XR0 113 
J 0
(-2206 4485);
DISPLAY 0.638298 (-2206 4485);
PAINT MONO (-2206 4485);
WIRE 16 -1 (-2100 4625)(-2100 4475);
WIRE 16 -1 (-2500 4625)(-2100 4625);
WIRE 16 -1 (-2700 4150)(-3075 4150);
FORCEPROP 0 LAST SIG_NAME PWRGD_CPU0_G
J 0
(-3075 4160);
DISPLAY 0.617021 (-3075 4160);
PAINT ORANGE (-3075 4160);
WIRE 16 -1 (-3075 4625)(-2700 4625);
FORCEPROP 0 LAST SIG_NAME JTAG_MCP_TCK
J 0
(-3075 4635);
DISPLAY 0.617021 (-3075 4635);
PAINT ORANGE (-3075 4635);
WIRE 16 -1 (-3075 4375)(-2700 4375);
FORCEPROP 2 LAST SIG_NAME JTAG_MCP_TMS
J 0
(-3075 4385);
DISPLAY 0.617021 (-3075 4385);
PAINT ORANGE (-3075 4385);
WIRE 16 -1 (-1100 3675)(-1725 3675);
FORCEPROP 2 LAST SIG_NAME FM_CPU1_CD_PRES
J 0
(-1625 3685);
DISPLAY 0.617021 (-1625 3685);
PAINT ORANGE (-1625 3685);
WIRE 16 -1 (-1100 3575)(-1725 3575);
FORCEPROP 0 LAST SIG_NAME JTAG_MCP_CPU1_TDO
J 0
(-1625 3585);
DISPLAY 0.617021 (-1625 3585);
PAINT ORANGE (-1625 3585);
WIRE 16 -1 (-1725 3475)(-1100 3475);
FORCEPROP 0 LAST SIG_NAME JTAG_MCP_CPU0_TDO
J 0
(-1625 3485);
DISPLAY 0.617021 (-1625 3485);
PAINT ORANGE (-1625 3485);
WIRE 16 -1 (-1150 2475)(-1775 2475);
FORCEPROP 2 LAST SIG_NAME FM_CPU0_CD_PRES
J 0
(-1675 2485);
DISPLAY 0.617021 (-1675 2485);
PAINT ORANGE (-1675 2485);
WIRE 16 -1 (-1150 2375)(-1775 2375);
FORCEPROP 0 LAST SIG_NAME JTAG_MCP_CPU1_TDI
J 0
(-1675 2385);
DISPLAY 0.617021 (-1675 2385);
PAINT ORANGE (-1675 2385);
WIRE 16 -1 (-1775 2275)(-1150 2275);
FORCEPROP 0 LAST SIG_NAME JTAG_MCP_CPU0_TDI
J 0
(-1675 2285);
DISPLAY 0.617021 (-1675 2285);
PAINT ORANGE (-1675 2285);
WIRE 16 -1 (-800 850)(-1250 850);
FORCEPROP 0 LAST SIG_NAME JTAG_MCP_CPU1_TDI
J 0
(-1160 860);
DISPLAY 0.617021 (-1160 860);
PAINT ORANGE (-1160 860);
WIRE 16 -1 (-1750 800)(-2425 800);
FORCEPROP 0 LAST SIG_NAME FM_CPU0_AND_CPU1_MCP_PRES
J 0
(-2410 810);
DISPLAY 0.617021 (-2410 810);
PAINT ORANGE (-2410 810);
WIRE 16 -1 (-1750 850)(-2425 850);
FORCEPROP 0 LAST SIG_NAME JTAG_MCP_CPU0_TDO
J 0
(-2410 860);
DISPLAY 0.617021 (-2410 860);
PAINT ORANGE (-2410 860);
WIRE 16 -1 (-2425 3525)(-2950 3525);
FORCEPROP 0 LAST SIG_NAME JTAG_MCP_MUX_TDO
J 0
(-2960 3535);
DISPLAY 0.617021 (-2960 3535);
PAINT ORANGE (-2960 3535);
WIRE 16 -1 (-2475 2325)(-3000 2325);
FORCEPROP 0 LAST SIG_NAME JTAG_MCP_MUX_TDI
J 0
(-3010 2335);
DISPLAY 0.617021 (-3010 2335);
PAINT ORANGE (-3010 2335);
DOT 1 (-1600 2000);
DOT 1 (-1275 2000);
DOT 1 (-1275 1575);
DOT 1 (-1250 2800);
DOT 1 (-1550 3200);
DOT 1 (-1250 3200);
DOT 1 (-1150 4275);
DOT 1 (-1100 4800);
DOT 1 (2150 2250);
DOT 1 (2125 2825);
DOT 1 (2125 3375);
DOT 1 (2600 4400);
DOT 1 (3575 1200);
DOT 1 (3425 1200);
DOT 1 (3175 1200);
FORCENOTE
ROOM=DEBUG
(-2525 150) 0;
DISPLAY LEFT (-2525 150);
DISPLAY 1.021277 (-2525 150);
PAINT PURPLE (-2525 150);
FORCENOTE
MCP OR WFR PULL UPS AND PULL DOWNS
(150 4825) 0;
DISPLAY LEFT (150 4825);
DISPLAY 1.595745 (150 4825);
PAINT PURPLE (150 4825);
QUIT
